G04 ================== begin FILE IDENTIFICATION RECORD ==================*
G04 Layout Name:  9054_F0T_PDB_BD_GPU_F_V04_1213_1550.brd*
G04 Film Name:    gnd2*
G04 File Format:  Gerber RS274X*
G04 File Origin:  Cadence Allegro 17.2-S081*
G04 Origin Date:  Wed Dec 28 10:19:02 2022*
G04 *
G04 Layer:  DRAWING FORMAT/TITLE_BLOCK_A*
G04 Layer:  PIN/SPECIAL_DRILL*
G04 Layer:  VIA CLASS/GND2*
G04 Layer:  PIN/GND2*
G04 Layer:  MANUFACTURING/PHOTOPLOT_OUTLINE*
G04 Layer:  ETCH/GND2*
G04 Layer:  DRAWING FORMAT/TITLE_BLOCK*
G04 Layer:  DRAWING FORMAT/TITLE_DATA_GND2*
G04 *
G04 Offset:    (0.00 0.00)*
G04 Mirror:    No*
G04 Mode:      Negative*
G04 Rotation:  0*
G04 FullContactRelief:  No*
G04 UndefLineWidth:     6.00*
G04 ================== end FILE IDENTIFICATION RECORD ====================*
%FSLAX25Y25*MOIN*%
%IR0*IPPOS*OFA0.00000B0.00000*MIA0B0*SFA1.00000B1.00000*%
%ADD17C,.03*%
%ADD47C,.061*%
%ADD20C,.07*%
%ADD42C,.026*%
%ADD19C,.07*%
%AMMACRO15*
4,1,36,0.0,.01,
-.001736,.009848,
-.00342,.009397,
-.005,.00866,
-.006428,.00766,
-.00766,.006428,
-.00866,.005,
-.009397,.00342,
-.009848,.001736,
-.01,0.0,
-.009848,-.001736,
-.009397,-.00342,
-.00866,-.005,
-.00766,-.006428,
-.006428,-.00766,
-.005,-.00866,
-.00342,-.009397,
-.001736,-.009848,
0.0,-.01,
.001736,-.009848,
.00342,-.009397,
.005,-.00866,
.006428,-.00766,
.00766,-.006428,
.00866,-.005,
.009397,-.00342,
.009848,-.001736,
.01,0.0,
.009848,.001736,
.009397,.00342,
.00866,.005,
.00766,.006428,
.006428,.00766,
.005,.00866,
.00342,.009397,
.001736,.009848,
0.0,.01,
0.0*
%
%ADD15MACRO15*%
%AMMACRO29*
4,1,36,.0025,0.0,
.002462,.000434,
.002349,.000855,
.002165,.00125,
.001915,.001607,
.001607,.001915,
.00125,.002165,
.000855,.002349,
.000434,.002462,
0.0,.0025,
-.000434,.002462,
-.000855,.002349,
-.00125,.002165,
-.001607,.001915,
-.001915,.001607,
-.002165,.00125,
-.002349,.000855,
-.002462,.000434,
-.0025,0.0,
-.002462,-.000434,
-.002349,-.000855,
-.002165,-.00125,
-.001915,-.001607,
-.001607,-.001915,
-.00125,-.002165,
-.000855,-.002349,
-.000434,-.002462,
0.0,-.0025,
.000434,-.002462,
.000855,-.002349,
.00125,-.002165,
.001607,-.001915,
.001915,-.001607,
.002165,-.00125,
.002349,-.000855,
.002462,-.000434,
.0025,0.0,
270.*
%
%ADD29MACRO29*%
%AMMACRO28*
4,1,36,.0025,0.0,
.002462,.000434,
.002349,.000855,
.002165,.00125,
.001915,.001607,
.001607,.001915,
.00125,.002165,
.000855,.002349,
.000434,.002462,
0.0,.0025,
-.000434,.002462,
-.000855,.002349,
-.00125,.002165,
-.001607,.001915,
-.001915,.001607,
-.002165,.00125,
-.002349,.000855,
-.002462,.000434,
-.0025,0.0,
-.002462,-.000434,
-.002349,-.000855,
-.002165,-.00125,
-.001915,-.001607,
-.001607,-.001915,
-.00125,-.002165,
-.000855,-.002349,
-.000434,-.002462,
0.0,-.0025,
.000434,-.002462,
.000855,-.002349,
.00125,-.002165,
.001607,-.001915,
.001915,-.001607,
.002165,-.00125,
.002349,-.000855,
.002462,-.000434,
.0025,0.0,
180.*
%
%ADD28MACRO28*%
%ADD37C,.066*%
%ADD34C,.06015*%
%ADD31C,.087*%
%AMMACRO21*
4,1,36,0.0,.0135,
-.002344,.013295,
-.004617,.012686,
-.00675,.011691,
-.008678,.010342,
-.010342,.008678,
-.011691,.00675,
-.012686,.004617,
-.013295,.002344,
-.0135,0.0,
-.013295,-.002344,
-.012686,-.004617,
-.011691,-.00675,
-.010342,-.008678,
-.008678,-.010342,
-.00675,-.011691,
-.004617,-.012686,
-.002344,-.013295,
0.0,-.0135,
.002344,-.013295,
.004617,-.012686,
.00675,-.011691,
.008678,-.010342,
.010342,-.008678,
.011691,-.00675,
.012686,-.004617,
.013295,-.002344,
.0135,0.0,
.013295,.002344,
.012686,.004617,
.011691,.00675,
.010342,.008678,
.008678,.010342,
.00675,.011691,
.004617,.012686,
.002344,.013295,
0.0,.0135,
0.0*
%
%ADD21MACRO21*%
%AMMACRO43*
4,1,17,.09027,.06198,
.099661,.045363,
.106024,.027368,
.109166,.008541,
.108991,-.010545,
.105504,-.029311,
.098811,-.047186,
.09027,-.06198,
.0953,-.06701,
.105488,-.049443,
.112471,-.030374,
.116037,-.010382,
.116077,.009925,
.11259,.029931,
.105682,.049027,
.095563,.066634,
.0953,.06701,
.09027,.06198,
90.*
4,1,17,.06198,-.09027,
.045363,-.099661,
.027368,-.106024,
.008541,-.109166,
-.010545,-.108991,
-.029311,-.105504,
-.047186,-.098811,
-.06198,-.09027,
-.06701,-.0953,
-.049443,-.105488,
-.030374,-.112471,
-.010382,-.116037,
.009925,-.116077,
.029931,-.11259,
.049027,-.105682,
.066634,-.095563,
.06701,-.0953,
.06198,-.09027,
90.*
4,1,17,-.09027,-.06198,
-.099661,-.045363,
-.106024,-.027368,
-.109166,-.008541,
-.108991,.010545,
-.105504,.029311,
-.098811,.047186,
-.09027,.06198,
-.0953,.06701,
-.105488,.049443,
-.112471,.030374,
-.116037,.010382,
-.116077,-.009925,
-.11259,-.029931,
-.105682,-.049027,
-.095563,-.066634,
-.0953,-.06701,
-.09027,-.06198,
90.*
4,1,17,-.06198,.09027,
-.045363,.099661,
-.027368,.106024,
-.008541,.109166,
.010545,.108991,
.029311,.105504,
.047186,.098811,
.06198,.09027,
.06701,.0953,
.049443,.105488,
.030374,.112471,
.010382,.116037,
-.009925,.116077,
-.029931,.11259,
-.049027,.105682,
-.066634,.095563,
-.06701,.0953,
-.06198,.09027,
90.*
%
%ADD43MACRO43*%
%ADD18C,.04952*%
%AMMACRO45*
4,1,15,.02475,.01414,
.026829,.009627,
.028094,.004822,
.028504,-.000129,
.028049,-.005077,
.026741,-.009871,
.02475,-.01414,
.02984,-.01923,
.032726,-.013756,
.034617,-.007864,
.035457,-.001734,
.03522,.00445,
.033912,.010498,
.031574,.016227,
.02984,.01923,
.02475,.01414,
90.*
4,1,15,.01414,-.02475,
.009627,-.026829,
.004822,-.028094,
-.000129,-.028504,
-.005077,-.028049,
-.009871,-.026741,
-.01414,-.02475,
-.01923,-.02984,
-.013756,-.032726,
-.007864,-.034617,
-.001734,-.035457,
.00445,-.03522,
.010498,-.033912,
.016227,-.031574,
.01923,-.02984,
.01414,-.02475,
90.*
4,1,15,-.02475,-.01414,
-.026829,-.009627,
-.028094,-.004822,
-.028504,.000129,
-.028049,.005077,
-.026741,.009871,
-.02475,.01414,
-.02984,.01923,
-.032726,.013756,
-.034617,.007864,
-.035457,.001734,
-.03522,-.00445,
-.033912,-.010498,
-.031574,-.016227,
-.02984,-.01923,
-.02475,-.01414,
90.*
4,1,15,-.01414,.02475,
-.009627,.026829,
-.004822,.028094,
.000129,.028504,
.005077,.028049,
.009871,.026741,
.01414,.02475,
.01923,.02984,
.013756,.032726,
.007864,.034617,
.001734,.035457,
-.00445,.03522,
-.010498,.033912,
-.016227,.031574,
-.01923,.02984,
-.01414,.02475,
90.*
%
%ADD45MACRO45*%
%AMMACRO38*
4,1,16,.02657,.01597,
.02894,.011114,
.03043,.005919,
.030995,.000545,
.030619,-.004845,
.029313,-.010088,
.027115,-.015025,
.02657,-.01597,
.03164,-.02104,
.034813,-.015226,
.036928,-.00895,
.037921,-.002401,
.037762,.00422,
.036455,.010713,
.034041,.016881,
.03164,.02104,
.02657,.01597,
90.*
4,1,16,.01597,-.02657,
.011114,-.02894,
.005919,-.03043,
.000545,-.030995,
-.004845,-.030619,
-.010088,-.029313,
-.015025,-.027115,
-.01597,-.02657,
-.02104,-.03164,
-.015226,-.034813,
-.00895,-.036928,
-.002401,-.037921,
.00422,-.037762,
.010713,-.036455,
.016881,-.034041,
.02104,-.03164,
.01597,-.02657,
90.*
4,1,16,-.02657,-.01597,
-.02894,-.011114,
-.03043,-.005919,
-.030995,-.000545,
-.030619,.004845,
-.029313,.010088,
-.027115,.015025,
-.02657,.01597,
-.03164,.02104,
-.034813,.015226,
-.036928,.00895,
-.037921,.002401,
-.037762,-.00422,
-.036455,-.010713,
-.034041,-.016881,
-.03164,-.02104,
-.02657,-.01597,
90.*
4,1,16,-.01597,.02657,
-.011114,.02894,
-.005919,.03043,
-.000545,.030995,
.004845,.030619,
.010088,.029313,
.015025,.027115,
.01597,.02657,
.02104,.03164,
.015226,.034813,
.00895,.036928,
.002401,.037921,
-.00422,.037762,
-.010713,.036455,
-.016881,.034041,
-.02104,.03164,
-.01597,.02657,
90.*
%
%ADD38MACRO38*%
%AMMACRO41*
4,1,15,.03682,.01914,
.039584,.012455,
.041146,.005393,
.041457,-.001834,
.040509,-.009005,
.03833,-.015903,
.03682,-.01914,
.04197,-.0243,
.045552,-.016643,
.04775,-.00848,
.048497,-.000059,
.047771,.008363,
.045593,.016531,
.042029,.024197,
.04197,.0243,
.03682,.01914,
90.*
4,1,15,.01914,-.03682,
.012455,-.039584,
.005393,-.041146,
-.001834,-.041457,
-.009005,-.040509,
-.015903,-.03833,
-.01914,-.03682,
-.0243,-.04197,
-.016643,-.045552,
-.00848,-.04775,
-.000059,-.048497,
.008363,-.047771,
.016531,-.045593,
.024197,-.042029,
.0243,-.04197,
.01914,-.03682,
90.*
4,1,15,-.03682,-.01914,
-.039584,-.012455,
-.041146,-.005393,
-.041457,.001834,
-.040509,.009005,
-.03833,.015903,
-.03682,.01914,
-.04197,.0243,
-.045552,.016643,
-.04775,.00848,
-.048497,.000059,
-.047771,-.008363,
-.045593,-.016531,
-.042029,-.024197,
-.04197,-.0243,
-.03682,-.01914,
90.*
4,1,15,-.01914,.03682,
-.012455,.039584,
-.005393,.041146,
.001834,.041457,
.009005,.040509,
.015903,.03833,
.01914,.03682,
.0243,.04197,
.016643,.045552,
.00848,.04775,
.000059,.048497,
-.008363,.047771,
-.016531,.045593,
-.024197,.042029,
-.0243,.04197,
-.01914,.03682,
90.*
%
%ADD41MACRO41*%
%AMMACRO40*
4,1,15,-.03682,.01914,
-.039584,.012455,
-.041146,.005393,
-.041457,-.001834,
-.040509,-.009005,
-.03833,-.015903,
-.03682,-.01914,
-.04197,-.0243,
-.045552,-.016643,
-.04775,-.00848,
-.048497,-.000059,
-.047771,.008363,
-.045593,.016531,
-.042029,.024197,
-.04197,.0243,
-.03682,.01914,
90.*
4,1,15,-.01914,-.03682,
-.012455,-.039584,
-.005393,-.041146,
.001834,-.041457,
.009005,-.040509,
.015903,-.03833,
.01914,-.03682,
.0243,-.04197,
.016643,-.045552,
.00848,-.04775,
.000059,-.048497,
-.008363,-.047771,
-.016531,-.045593,
-.024197,-.042029,
-.0243,-.04197,
-.01914,-.03682,
90.*
4,1,15,.03682,-.01914,
.039584,-.012455,
.041146,-.005393,
.041457,.001834,
.040509,.009005,
.03833,.015903,
.03682,.01914,
.04197,.0243,
.045552,.016643,
.04775,.00848,
.048497,.000059,
.047771,-.008363,
.045593,-.016531,
.042029,-.024197,
.04197,-.0243,
.03682,-.01914,
90.*
4,1,15,.01914,.03682,
.012455,.039584,
.005393,.041146,
-.001834,.041457,
-.009005,.040509,
-.015903,.03833,
-.01914,.03682,
-.0243,.04197,
-.016643,.045552,
-.00848,.04775,
-.000059,.048497,
.008363,.047771,
.016531,.045593,
.024197,.042029,
.0243,.04197,
.01914,.03682,
90.*
%
%ADD40MACRO40*%
%ADD25C,.113*%
%AMMACRO14*
4,1,36,0.0,.005,
.000868,.004924,
.00171,.004698,
.0025,.00433,
.003214,.00383,
.00383,.003214,
.00433,.0025,
.004698,.00171,
.004924,.000868,
.005,0.0,
.004924,-.000868,
.004698,-.00171,
.00433,-.0025,
.00383,-.003214,
.003214,-.00383,
.0025,-.00433,
.00171,-.004698,
.000868,-.004924,
0.0,-.005,
-.000868,-.004924,
-.00171,-.004698,
-.0025,-.00433,
-.003214,-.00383,
-.00383,-.003214,
-.00433,-.0025,
-.004698,-.00171,
-.004924,-.000868,
-.005,0.0,
-.004924,.000868,
-.004698,.00171,
-.00433,.0025,
-.00383,.003214,
-.003214,.00383,
-.0025,.00433,
-.00171,.004698,
-.000868,.004924,
0.0,.005,
180.*
%
%ADD14MACRO14*%
%ADD27C,.115*%
%ADD46C,.116*%
%ADD10C,.125*%
%ADD23C,.155*%
%ADD35C,.256*%
%AMMACRO26*
4,1,36,0.0,.0135,
-.002344,.013295,
-.004617,.012686,
-.00675,.011691,
-.008678,.010342,
-.010342,.008678,
-.011691,.00675,
-.012686,.004617,
-.013295,.002344,
-.0135,0.0,
-.013295,-.002344,
-.012686,-.004617,
-.011691,-.00675,
-.010342,-.008678,
-.008678,-.010342,
-.00675,-.011691,
-.004617,-.012686,
-.002344,-.013295,
0.0,-.0135,
.002344,-.013295,
.004617,-.012686,
.00675,-.011691,
.008678,-.010342,
.010342,-.008678,
.011691,-.00675,
.012686,-.004617,
.013295,-.002344,
.0135,0.0,
.013295,.002344,
.012686,.004617,
.011691,.00675,
.010342,.008678,
.008678,.010342,
.00675,.011691,
.004617,.012686,
.002344,.013295,
0.0,.0135,
270.*
%
%ADD26MACRO26*%
%AMMACRO22*
4,1,36,0.0,.0135,
-.002344,.013295,
-.004617,.012686,
-.00675,.011691,
-.008678,.010342,
-.010342,.008678,
-.011691,.00675,
-.012686,.004617,
-.013295,.002344,
-.0135,0.0,
-.013295,-.002344,
-.012686,-.004617,
-.011691,-.00675,
-.010342,-.008678,
-.008678,-.010342,
-.00675,-.011691,
-.004617,-.012686,
-.002344,-.013295,
0.0,-.0135,
.002344,-.013295,
.004617,-.012686,
.00675,-.011691,
.008678,-.010342,
.010342,-.008678,
.011691,-.00675,
.012686,-.004617,
.013295,-.002344,
.0135,0.0,
.013295,.002344,
.012686,.004617,
.011691,.00675,
.010342,.008678,
.008678,.010342,
.00675,.011691,
.004617,.012686,
.002344,.013295,
0.0,.0135,
180.*
%
%ADD22MACRO22*%
%AMMACRO24*
4,1,36,.0025,0.0,
.002462,.000434,
.002349,.000855,
.002165,.00125,
.001915,.001607,
.001607,.001915,
.00125,.002165,
.000855,.002349,
.000434,.002462,
0.0,.0025,
-.000434,.002462,
-.000855,.002349,
-.00125,.002165,
-.001607,.001915,
-.001915,.001607,
-.002165,.00125,
-.002349,.000855,
-.002462,.000434,
-.0025,0.0,
-.002462,-.000434,
-.002349,-.000855,
-.002165,-.00125,
-.001915,-.001607,
-.001607,-.001915,
-.00125,-.002165,
-.000855,-.002349,
-.000434,-.002462,
0.0,-.0025,
.000434,-.002462,
.000855,-.002349,
.00125,-.002165,
.001607,-.001915,
.001915,-.001607,
.002165,-.00125,
.002349,-.000855,
.002462,-.000434,
.0025,0.0,
90.*
%
%ADD24MACRO24*%
%ADD36C,.187*%
%AMMACRO33*
4,1,36,0.0,.019,
-.003299,.018711,
-.006498,.017854,
-.0095,.016454,
-.012213,.014555,
-.014555,.012213,
-.016454,.0095,
-.017854,.006498,
-.018711,.003299,
-.019,0.0,
-.018711,-.003299,
-.017854,-.006498,
-.016454,-.0095,
-.014555,-.012213,
-.012213,-.014555,
-.0095,-.016454,
-.006498,-.017854,
-.003299,-.018711,
0.0,-.019,
.003299,-.018711,
.006498,-.017854,
.0095,-.016454,
.012213,-.014555,
.014555,-.012213,
.016454,-.0095,
.017854,-.006498,
.018711,-.003299,
.019,0.0,
.018711,.003299,
.017854,.006498,
.016454,.0095,
.014555,.012213,
.012213,.014555,
.0095,.016454,
.006498,.017854,
.003299,.018711,
0.0,.019,
180.*
%
%ADD33MACRO33*%
%AMMACRO11*
4,1,36,.0025,0.0,
.002462,.000434,
.002349,.000855,
.002165,.00125,
.001915,.001607,
.001607,.001915,
.00125,.002165,
.000855,.002349,
.000434,.002462,
0.0,.0025,
-.000434,.002462,
-.000855,.002349,
-.00125,.002165,
-.001607,.001915,
-.001915,.001607,
-.002165,.00125,
-.002349,.000855,
-.002462,.000434,
-.0025,0.0,
-.002462,-.000434,
-.002349,-.000855,
-.002165,-.00125,
-.001915,-.001607,
-.001607,-.001915,
-.00125,-.002165,
-.000855,-.002349,
-.000434,-.002462,
0.0,-.0025,
.000434,-.002462,
.000855,-.002349,
.00125,-.002165,
.001607,-.001915,
.001915,-.001607,
.002165,-.00125,
.002349,-.000855,
.002462,-.000434,
.0025,0.0,
0.0*
%
%ADD11MACRO11*%
%ADD16C,.188*%
%AMMACRO44*
4,1,21,-.0075,-.06379,
-.0075,-.0709,
-.015443,-.068892,
-.022917,-.065536,
-.029695,-.060932,
-.03557,-.055222,
-.040364,-.048578,
-.043932,-.041203,
-.046165,-.03332,
-.046995,-.025169,
-.047,-.0245,
-.047,-.0075,
-.04,-.0075,
-.04,-.0245,
-.039392,-.031446,
-.037588,-.038181,
-.034641,-.0445,
-.030642,-.050211,
-.025712,-.055141,
-.02,-.05914,
-.013681,-.062087,
-.0075,-.06379,
90.*
4,1,21,.0075,-.0709,
.0075,-.06379,
.014209,-.061891,
.020486,-.058856,
.02614,-.054776,
.031001,-.049777,
.034919,-.04401,
.037776,-.03765,
.039486,-.030891,
.04,-.0245,
.04,-.0075,
.047,-.0075,
.047,-.0245,
.046286,-.032662,
.044165,-.040576,
.040703,-.048001,
.036003,-.054713,
.03021,-.060506,
.023499,-.065205,
.016073,-.068668,
.008159,-.070789,
.0075,-.0709,
90.*
4,1,21,-.0075,.0709,
-.0075,.06379,
-.014209,.061891,
-.020486,.058856,
-.02614,.054776,
-.031001,.049777,
-.034919,.04401,
-.037776,.03765,
-.039486,.030891,
-.04,.0245,
-.04,.0075,
-.047,.0075,
-.047,.0245,
-.046286,.032662,
-.044165,.040576,
-.040703,.048001,
-.036003,.054713,
-.03021,.060506,
-.023499,.065205,
-.016073,.068668,
-.008159,.070789,
-.0075,.0709,
90.*
4,1,21,.0075,.06379,
.0075,.0709,
.015443,.068892,
.022917,.065536,
.029695,.060932,
.03557,.055222,
.040364,.048578,
.043932,.041203,
.046165,.03332,
.046995,.025169,
.047,.0245,
.047,.0075,
.04,.0075,
.04,.0245,
.039392,.031446,
.037588,.038181,
.034641,.0445,
.030642,.050211,
.025712,.055141,
.02,.05914,
.013681,.062087,
.0075,.06379,
90.*
%
%ADD44MACRO44*%
%AMMACRO39*
4,1,16,.02657,.01597,
.02894,.011114,
.03043,.005919,
.030995,.000545,
.030619,-.004845,
.029313,-.010088,
.027115,-.015025,
.02657,-.01597,
.03164,-.02104,
.034813,-.015226,
.036928,-.00895,
.037921,-.002401,
.037762,.00422,
.036455,.010713,
.034041,.016881,
.03164,.02104,
.02657,.01597,
270.*
4,1,16,.01597,-.02657,
.011114,-.02894,
.005919,-.03043,
.000545,-.030995,
-.004845,-.030619,
-.010088,-.029313,
-.015025,-.027115,
-.01597,-.02657,
-.02104,-.03164,
-.015226,-.034813,
-.00895,-.036928,
-.002401,-.037921,
.00422,-.037762,
.010713,-.036455,
.016881,-.034041,
.02104,-.03164,
.01597,-.02657,
270.*
4,1,16,-.02657,-.01597,
-.02894,-.011114,
-.03043,-.005919,
-.030995,-.000545,
-.030619,.004845,
-.029313,.010088,
-.027115,.015025,
-.02657,.01597,
-.03164,.02104,
-.034813,.015226,
-.036928,.00895,
-.037921,.002401,
-.037762,-.00422,
-.036455,-.010713,
-.034041,-.016881,
-.03164,-.02104,
-.02657,-.01597,
270.*
4,1,16,-.01597,.02657,
-.011114,.02894,
-.005919,.03043,
-.000545,.030995,
.004845,.030619,
.010088,.029313,
.015025,.027115,
.01597,.02657,
.02104,.03164,
.015226,.034813,
.00895,.036928,
.002401,.037921,
-.00422,.037762,
-.010713,.036455,
-.016881,.034041,
-.02104,.03164,
-.01597,.02657,
270.*
%
%ADD39MACRO39*%
%AMMACRO12*
4,1,18,.10783,.07955,
.120006,.059617,
.128535,.037873,
.133159,.014977,
.133736,-.008373,
.130251,-.031469,
.122807,-.053609,
.111633,-.074119,
.10783,-.07955,
.11284,-.08455,
.125808,-.063671,
.134953,-.040857,
.139997,-.016802,
.140788,.007763,
.137301,.032093,
.129642,.055447,
.118045,.077117,
.11284,.08455,
.10783,.07955,
180.*
4,1,18,.07955,-.10783,
.059617,-.120006,
.037873,-.128535,
.014977,-.133159,
-.008373,-.133736,
-.031469,-.130251,
-.053609,-.122807,
-.074119,-.111633,
-.07955,-.10783,
-.08455,-.11284,
-.063671,-.125808,
-.040857,-.134953,
-.016802,-.139997,
.007763,-.140788,
.032093,-.137301,
.055447,-.129642,
.077117,-.118045,
.08455,-.11284,
.07955,-.10783,
180.*
4,1,18,-.10783,-.07955,
-.120006,-.059617,
-.128535,-.037873,
-.133159,-.014977,
-.133736,.008373,
-.130251,.031469,
-.122807,.053609,
-.111633,.074119,
-.10783,.07955,
-.11284,.08455,
-.125808,.063671,
-.134953,.040857,
-.139997,.016802,
-.140788,-.007763,
-.137301,-.032093,
-.129642,-.055447,
-.118045,-.077117,
-.11284,-.08455,
-.10783,-.07955,
180.*
4,1,18,-.07955,.10783,
-.059617,.120006,
-.037873,.128535,
-.014977,.133159,
.008373,.133736,
.031469,.130251,
.053609,.122807,
.074119,.111633,
.07955,.10783,
.08455,.11284,
.063671,.125808,
.040857,.134953,
.016802,.139997,
-.007763,.140788,
-.032093,.137301,
-.055447,.129642,
-.077117,.118045,
-.08455,.11284,
-.07955,.10783,
180.*
%
%ADD12MACRO12*%
%AMMACRO30*
4,1,15,.03682,.01914,
.039584,.012455,
.041146,.005393,
.041457,-.001834,
.040509,-.009005,
.03833,-.015903,
.03682,-.01914,
.04197,-.0243,
.045552,-.016643,
.04775,-.00848,
.048497,-.000059,
.047771,.008363,
.045593,.016531,
.042029,.024197,
.04197,.0243,
.03682,.01914,
270.*
4,1,15,.01914,-.03682,
.012455,-.039584,
.005393,-.041146,
-.001834,-.041457,
-.009005,-.040509,
-.015903,-.03833,
-.01914,-.03682,
-.0243,-.04197,
-.016643,-.045552,
-.00848,-.04775,
-.000059,-.048497,
.008363,-.047771,
.016531,-.045593,
.024197,-.042029,
.0243,-.04197,
.01914,-.03682,
270.*
4,1,15,-.03682,-.01914,
-.039584,-.012455,
-.041146,-.005393,
-.041457,.001834,
-.040509,.009005,
-.03833,.015903,
-.03682,.01914,
-.04197,.0243,
-.045552,.016643,
-.04775,.00848,
-.048497,.000059,
-.047771,-.008363,
-.045593,-.016531,
-.042029,-.024197,
-.04197,-.0243,
-.03682,-.01914,
270.*
4,1,15,-.01914,.03682,
-.012455,.039584,
-.005393,.041146,
.001834,.041457,
.009005,.040509,
.015903,.03833,
.01914,.03682,
.0243,.04197,
.016643,.045552,
.00848,.04775,
.000059,.048497,
-.008363,.047771,
-.016531,.045593,
-.024197,.042029,
-.0243,.04197,
-.01914,.03682,
270.*
%
%ADD30MACRO30*%
%AMMACRO32*
4,1,15,-.03682,.01914,
-.039584,.012455,
-.041146,.005393,
-.041457,-.001834,
-.040509,-.009005,
-.03833,-.015903,
-.03682,-.01914,
-.04197,-.0243,
-.045552,-.016643,
-.04775,-.00848,
-.048497,-.000059,
-.047771,.008363,
-.045593,.016531,
-.042029,.024197,
-.04197,.0243,
-.03682,.01914,
270.*
4,1,15,-.01914,-.03682,
-.012455,-.039584,
-.005393,-.041146,
.001834,-.041457,
.009005,-.040509,
.015903,-.03833,
.01914,-.03682,
.0243,-.04197,
.016643,-.045552,
.00848,-.04775,
.000059,-.048497,
-.008363,-.047771,
-.016531,-.045593,
-.024197,-.042029,
-.0243,-.04197,
-.01914,-.03682,
270.*
4,1,15,.03682,-.01914,
.039584,-.012455,
.041146,-.005393,
.041457,.001834,
.040509,.009005,
.03833,.015903,
.03682,.01914,
.04197,.0243,
.045552,.016643,
.04775,.00848,
.048497,.000059,
.047771,-.008363,
.045593,-.016531,
.042029,-.024197,
.04197,-.0243,
.03682,-.01914,
270.*
4,1,15,.01914,.03682,
.012455,.039584,
.005393,.041146,
-.001834,.041457,
-.009005,.040509,
-.015903,.03833,
-.01914,.03682,
-.0243,.04197,
-.016643,.045552,
-.00848,.04775,
-.000059,.048497,
.008363,.047771,
.016531,.045593,
.024197,.042029,
.0243,.04197,
.01914,.03682,
270.*
%
%ADD32MACRO32*%
%ADD48C,.02*%
%ADD49C,.006*%
%ADD57C,.0801*%
%ADD56C,.07006*%
%ADD59C,.09558*%
%ADD60C,.11022*%
%ADD58C,.12006*%
%ADD55C,.11708*%
%ADD51C,.12608*%
%ADD54C,.13509*%
%ADD52C,.16506*%
%ADD50C,.28606*%
%ADD53C,.19806*%
G75*
%LPD*%
G75*
G36*
G01X-457143Y-1211429D02*
X4308572D01*
Y2242857D01*
X-457143D01*
Y-1211429D01*
G37*
%LPC*%
G75*
G36*
G01X1854331Y516776D02*
G02X1872012Y499095I-1J-17682D01*
G01Y85709D01*
G02X1854331Y68028I-17681J0D01*
G01X1751968D01*
G03X1730279Y46339I1J-21690D01*
G01Y19685D01*
G02X1712598Y2004I-17681J0D01*
G01X19685D01*
G02X2004Y19685I0J17681D01*
G01Y603543D01*
G02X19685Y621224I17681J0D01*
G01X102362D01*
G03X124051Y642913I0J21689D01*
G01Y656102D01*
G02X141732Y673783I17681J0D01*
G01X295276D01*
G02X312957Y656102I0J-17681D01*
G01Y634965D01*
G03X326698Y621224I14799J1058D01*
G01X328740D01*
G02X346421Y603543I0J-17681D01*
G01Y435039D01*
G03X377952Y403508I31532J1D01*
G01X1252385D01*
X1252389Y403512D01*
X1256109D01*
X1256113Y403508D01*
X1354331D01*
G03X1385862Y435039I0J31531D01*
G01Y603543D01*
G02X1403543Y621224I17681J0D01*
G01X1405512D01*
G03X1419327Y635039I0J13815D01*
G01Y656102D01*
G02X1437008Y673783I17681J0D01*
G01X1590551D01*
G02X1608232Y656102I0J-17681D01*
G01Y642913D01*
G03X1629921Y621224I21689J0D01*
G01X1712598D01*
G02X1730279Y603543I0J-17681D01*
G01Y538465D01*
G03X1751968Y516776I21690J0D01*
G01X1854331D01*
G37*
G36*
G01X1866142Y783851D02*
G02X1872016Y777977I0J-5874D01*
G01Y534528D01*
G02X1866142Y528654I-5874J0D01*
G01X1751968D01*
G02X1742157Y538465I1J9811D01*
G01Y603543D01*
G03X1712598Y633102I-29559J0D01*
G01X1640064D01*
G02X1630253Y642913I0J9811D01*
G01Y738607D01*
G03X1620379Y748481I-9874J0D01*
G01X1383858D01*
G03X1373984Y738607I0J-9874D01*
G01Y435039D01*
G02X1354331Y415386I-19653J0D01*
G01X1154764D01*
G02X1148890Y421260I0J5874D01*
G01Y479449D01*
G03X1135079Y493260I-13811J0D01*
G01X550827D01*
G03X537016Y479449I0J-13811D01*
G01Y421260D01*
G02X531142Y415386I-5874J0D01*
G01X377952D01*
G02X358299Y435039I0J19653D01*
G01Y738607D01*
G03X348425Y748481I-9874J0D01*
G01X111905D01*
G03X102031Y738607I0J-9874D01*
G01Y642913D01*
G02X92220Y633102I-9811J0D01*
G01X7874D01*
G02X2000Y638976I0J5874D01*
G01Y777977D01*
G02X7874Y783851I5874J0D01*
G01X1866142D01*
G37*
%LPD*%
G75*
G36*
G01X695332Y327292D02*
G02X696610Y327534I1279J-3260D01*
G01X696613D01*
G02Y320530I0J-3502D01*
G01X696610D01*
G02X695332Y320772I1J3502D01*
G03X695185I-73J-186D01*
G02X693907Y320530I-1279J3260D01*
G01X693904D01*
G02Y327534I0J3502D01*
G01X693907D01*
G02X695185Y327292I-1J-3502D01*
G03X695332I73J186D01*
G37*
G36*
G01X1320919Y197645D02*
G02X1320348Y197598I-572J3455D01*
G01X1320346D01*
G02X1323848Y201100I0J3502D01*
G02X1323142Y198991I-3503J0D01*
G03X1323527Y198355I319J-241D01*
G02X1324098Y198402I572J-3455D01*
G01X1324100D01*
G02X1320598Y194900I0J-3502D01*
G02X1321304Y197009I3503J0D01*
G03X1320919Y197645I-319J241D01*
G37*
G36*
G01Y153245D02*
G02X1320348Y153198I-572J3455D01*
G01X1320346D01*
G02X1323848Y156700I0J3502D01*
G02X1323142Y154591I-3503J0D01*
G03X1323527Y153955I319J-241D01*
G02X1324098Y154002I572J-3455D01*
G01X1324100D01*
G02X1320598Y150500I0J-3502D01*
G02X1321304Y152609I3503J0D01*
G03X1320919Y153245I-319J241D01*
G37*
G36*
G01X1563628Y664685D02*
Y664687D01*
G02X1568406Y669464I4778J-1D01*
G02X1572039Y667789I-1J-4779D01*
G03X1572191Y667719I152J130D01*
G01X1572495D01*
G03X1572647Y667789I0J200D01*
G02X1576280Y669464I3634J-3104D01*
G02X1581058Y664685I-1J-4779D01*
G02X1579384Y661052I-4779J0D01*
G03X1579314Y660900I130J-152D01*
G01Y660596D01*
G03X1579384Y660444I200J0D01*
G02Y653178I-3105J-3633D01*
G03X1579314Y653026I130J-152D01*
G01Y652722D01*
G03X1579384Y652570I200J0D01*
G02Y645304I-3105J-3633D01*
G03X1579314Y645152I130J-152D01*
G01Y644848D01*
G03X1579384Y644696I200J0D01*
G02Y637430I-3105J-3633D01*
G03X1579314Y637278I130J-152D01*
G01Y636974D01*
G03X1579384Y636822I200J0D01*
G02Y629556I-3105J-3633D01*
G03X1579314Y629404I130J-152D01*
G01Y629100D01*
G03X1579384Y628948I200J0D01*
G02Y621682I-3105J-3633D01*
G03X1579314Y621530I130J-152D01*
G01Y621226D01*
G03X1579384Y621074I200J0D01*
G02Y613808I-3105J-3633D01*
G03X1579314Y613656I130J-152D01*
G01Y613352D01*
G03X1579384Y613200I200J0D01*
G02Y605934I-3105J-3633D01*
G03X1579314Y605782I130J-152D01*
G01Y605478D01*
G03X1579384Y605326I200J0D01*
G02X1581058Y601693I-3105J-3633D01*
G01Y601691D01*
G02X1576280Y596914I-4778J1D01*
G02X1572647Y598589I1J4779D01*
G03X1572495Y598659I-152J-130D01*
G01X1572191D01*
G03X1572039Y598589I0J-200D01*
G02X1568406Y596914I-3634J3104D01*
G02X1563628Y601693I1J4779D01*
G02X1565302Y605326I4779J0D01*
G03X1565372Y605478I-130J152D01*
G01Y605782D01*
G03X1565302Y605934I-200J0D01*
G02Y613200I3105J3633D01*
G03X1565372Y613352I-130J152D01*
G01Y613656D01*
G03X1565302Y613808I-200J0D01*
G02Y621074I3105J3633D01*
G03X1565372Y621226I-130J152D01*
G01Y621530D01*
G03X1565302Y621682I-200J0D01*
G02Y628948I3105J3633D01*
G03X1565372Y629100I-130J152D01*
G01Y629404D01*
G03X1565302Y629556I-200J0D01*
G02Y636822I3105J3633D01*
G03X1565372Y636974I-130J152D01*
G01Y637278D01*
G03X1565302Y637430I-200J0D01*
G02Y644696I3105J3633D01*
G03X1565372Y644848I-130J152D01*
G01Y645152D01*
G03X1565302Y645304I-200J0D01*
G02Y652570I3105J3633D01*
G03X1565372Y652722I-130J152D01*
G01Y653026D01*
G03X1565302Y653178I-200J0D01*
G02Y660444I3105J3633D01*
G03X1565372Y660596I-130J152D01*
G01Y660900D01*
G03X1565302Y661052I-200J0D01*
G02X1563628Y664685I3105J3633D01*
G37*
G36*
G01X132524D02*
G02X137303Y669464I4779J0D01*
G02X140936Y667789I-1J-4779D01*
G03X141088Y667719I152J130D01*
G01X141392D01*
G03X141544Y667789I0J200D01*
G02X145177Y669464I3634J-3104D01*
G02X149956Y664685I0J-4779D01*
G02X148281Y661052I-4779J1D01*
G03X148211Y660900I130J-152D01*
G01Y660596D01*
G03X148281Y660444I200J0D01*
G02X149956Y656811I-3104J-3634D01*
G02X148281Y653178I-4779J1D01*
G03X148211Y653026I130J-152D01*
G01Y652722D01*
G03X148281Y652570I200J0D01*
G02X149956Y648937I-3104J-3634D01*
G02X148281Y645304I-4779J1D01*
G03X148211Y645152I130J-152D01*
G01Y644848D01*
G03X148281Y644696I200J0D01*
G02X149956Y641063I-3104J-3634D01*
G02X148281Y637430I-4779J1D01*
G03X148211Y637278I130J-152D01*
G01Y636974D01*
G03X148281Y636822I200J0D01*
G02X149956Y633189I-3104J-3634D01*
G02X148281Y629556I-4779J1D01*
G03X148211Y629404I130J-152D01*
G01Y629100D01*
G03X148281Y628948I200J0D01*
G02X149956Y625315I-3104J-3634D01*
G02X148281Y621682I-4779J1D01*
G03X148211Y621530I130J-152D01*
G01Y621226D01*
G03X148281Y621074I200J0D01*
G02X149956Y617441I-3104J-3634D01*
G02X148281Y613808I-4779J1D01*
G03X148211Y613656I130J-152D01*
G01Y613352D01*
G03X148281Y613200I200J0D01*
G02X149956Y609567I-3104J-3634D01*
G02X148281Y605934I-4779J1D01*
G03X148211Y605782I130J-152D01*
G01Y605478D01*
G03X148281Y605326I200J0D01*
G02X149956Y601693I-3104J-3634D01*
G02X145177Y596914I-4779J0D01*
G02X141544Y598589I1J4779D01*
G03X141392Y598659I-152J-130D01*
G01X141088D01*
G03X140936Y598589I0J-200D01*
G02X137303Y596914I-3634J3104D01*
G02X132524Y601693I0J4779D01*
G02X134199Y605326I4779J-1D01*
G03X134269Y605478I-130J152D01*
G01Y605782D01*
G03X134199Y605934I-200J0D01*
G02X132524Y609567I3104J3634D01*
G02X134199Y613200I4779J-1D01*
G03X134269Y613352I-130J152D01*
G01Y613656D01*
G03X134199Y613808I-200J0D01*
G02X132524Y617441I3104J3634D01*
G02X134199Y621074I4779J-1D01*
G03X134269Y621226I-130J152D01*
G01Y621530D01*
G03X134199Y621682I-200J0D01*
G02X132524Y625315I3104J3634D01*
G02X134199Y628948I4779J-1D01*
G03X134269Y629100I-130J152D01*
G01Y629404D01*
G03X134199Y629556I-200J0D01*
G02X132524Y633189I3104J3634D01*
G02X134199Y636822I4779J-1D01*
G03X134269Y636974I-130J152D01*
G01Y637278D01*
G03X134199Y637430I-200J0D01*
G02X132524Y641063I3104J3634D01*
G02X134199Y644696I4779J-1D01*
G03X134269Y644848I-130J152D01*
G01Y645152D01*
G03X134199Y645304I-200J0D01*
G02X132524Y648937I3104J3634D01*
G02X134199Y652570I4779J-1D01*
G03X134269Y652722I-130J152D01*
G01Y653026D01*
G03X134199Y653178I-200J0D01*
G02X132524Y656811I3104J3634D01*
G02X134199Y660444I4779J-1D01*
G03X134269Y660596I-130J152D01*
G01Y660900D01*
G03X134199Y661052I-200J0D01*
G02X132524Y664685I3104J3634D01*
G37*
G36*
G01X1530076Y638108D02*
X1530067Y638055D01*
X1530104Y637954D01*
X1530455Y637664D01*
X1530559Y637646D01*
X1530610Y637665D01*
G02X1532283Y637968I1675J-4476D01*
G02X1535916Y636293I-1J-4779D01*
G03X1536068Y636223I152J130D01*
G01X1536372D01*
G03X1536524Y636293I0J200D01*
G02X1540157Y637968I3634J-3104D01*
G02X1544936Y633189I0J-4779D01*
G02X1543261Y629556I-4779J1D01*
G03X1543191Y629404I130J-152D01*
G01Y629100D01*
G03X1543261Y628948I200J0D01*
G02X1544936Y625315I-3104J-3634D01*
G02X1543261Y621682I-4779J1D01*
G03X1543191Y621530I130J-152D01*
G01Y621226D01*
G03X1543261Y621074I200J0D01*
G02X1544936Y617441I-3104J-3634D01*
G02X1540157Y612662I-4779J0D01*
G02X1536524Y614337I1J4779D01*
G03X1536372Y614407I-152J-130D01*
G01X1536068D01*
G03X1535916Y614337I0J-200D01*
G02X1532283Y612662I-3634J3104D01*
G02X1527504Y617441I0J4779D01*
G02X1529179Y621074I4779J-1D01*
G03X1529249Y621226I-130J152D01*
G01Y621530D01*
G03X1529179Y621682I-200J0D01*
G02X1527504Y625315I3104J3634D01*
G02X1529179Y628948I4779J-1D01*
G03X1529249Y629100I-130J152D01*
G01Y629404D01*
G03X1529179Y629556I-200J0D01*
G02X1527504Y633189I3104J3634D01*
G02X1527518Y633540I4778J-15D01*
G01Y633542D01*
G03X1527431Y633722I-200J15D01*
G01X1527143Y633916D01*
G03X1526943Y633931I-113J-165D01*
G01X1526942Y633930D01*
G02X1521876I-2533J5164D01*
G01X1521875Y633931D01*
G03X1521675Y633916I-87J-180D01*
G01X1521387Y633722D01*
G03X1521300Y633542I113J-165D01*
G01Y633541D01*
G02X1521314Y633189I-4764J-366D01*
G02X1519639Y629556I-4779J1D01*
G03X1519569Y629404I130J-152D01*
G01Y629100D01*
G03X1519639Y628948I200J0D01*
G02X1521314Y625315I-3104J-3634D01*
G02X1519639Y621682I-4779J1D01*
G03X1519569Y621530I130J-152D01*
G01Y621226D01*
G03X1519639Y621074I200J0D01*
G02X1521314Y617441I-3104J-3634D01*
G02X1516535Y612662I-4779J0D01*
G02X1512902Y614337I1J4779D01*
G03X1512750Y614407I-152J-130D01*
G01X1512446D01*
G03X1512294Y614337I0J-200D01*
G02X1508661Y612662I-3634J3104D01*
G02X1503882Y617441I0J4779D01*
G02X1505557Y621074I4779J-1D01*
G03X1505627Y621226I-130J152D01*
G01Y621530D01*
G03X1505557Y621682I-200J0D01*
G02X1503882Y625315I3104J3634D01*
G02X1505557Y628948I4779J-1D01*
G03X1505627Y629100I-130J152D01*
G01Y629404D01*
G03X1505557Y629556I-200J0D01*
G02X1503882Y633189I3104J3634D01*
G02X1508661Y637968I4779J0D01*
G02X1512294Y636293I-1J-4779D01*
G03X1512446Y636223I152J130D01*
G01X1512750D01*
G03X1512902Y636293I0J200D01*
G02X1516535Y637968I3634J-3104D01*
G02X1518208Y637665I-2J-4779D01*
G01X1518259Y637646D01*
X1518363Y637664D01*
X1518714Y637954D01*
X1518751Y638055D01*
X1518742Y638108D01*
G02X1530076I5667J986D01*
G37*
G36*
G01X213541D02*
X213532Y638055D01*
X213569Y637954D01*
X213920Y637664D01*
X214024Y637646D01*
X214075Y637665D01*
G02X215748Y637968I1675J-4476D01*
G02X219381Y636293I-1J-4779D01*
G03X219533Y636223I152J130D01*
G01X219837D01*
G03X219989Y636293I0J200D01*
G02X223622Y637968I3634J-3104D01*
G02X228400Y633189I-1J-4779D01*
G02X226726Y629556I-4779J0D01*
G03X226656Y629404I130J-152D01*
G01Y629100D01*
G03X226726Y628948I200J0D01*
G02Y621682I-3105J-3633D01*
G03X226656Y621530I130J-152D01*
G01Y621226D01*
G03X226726Y621074I200J0D01*
G02X228400Y617441I-3105J-3633D01*
G01Y617439D01*
G02X223622Y612662I-4778J1D01*
G02X219989Y614337I1J4779D01*
G03X219837Y614407I-152J-130D01*
G01X219533D01*
G03X219381Y614337I0J-200D01*
G02X215748Y612662I-3634J3104D01*
G02X210970Y617441I1J4779D01*
G02X212644Y621074I4779J0D01*
G03X212714Y621226I-130J152D01*
G01Y621530D01*
G03X212644Y621682I-200J0D01*
G02Y628948I3105J3633D01*
G03X212714Y629100I-130J152D01*
G01Y629404D01*
G03X212644Y629556I-200J0D01*
G02X210970Y633189I3105J3633D01*
G02X210983Y633541I4778J0D01*
G01Y633542D01*
G03X210896Y633722I-200J15D01*
G01X210608Y633916D01*
G03X210408Y633931I-113J-165D01*
G01X210407Y633930D01*
G02X205341I-2533J5164D01*
G01X205340Y633931D01*
G03X205140Y633916I-87J-180D01*
G01X204852Y633722D01*
G03X204765Y633542I113J-165D01*
G01Y633541D01*
G02X204778Y633189I-4765J-352D01*
G02X203104Y629556I-4779J0D01*
G03X203034Y629404I130J-152D01*
G01Y629100D01*
G03X203104Y628948I200J0D01*
G02Y621682I-3105J-3633D01*
G03X203034Y621530I130J-152D01*
G01Y621226D01*
G03X203104Y621074I200J0D01*
G02X204778Y617441I-3105J-3633D01*
G01Y617439D01*
G02X200000Y612662I-4778J1D01*
G02X196367Y614337I1J4779D01*
G03X196215Y614407I-152J-130D01*
G01X195911D01*
G03X195759Y614337I0J-200D01*
G02X192126Y612662I-3634J3104D01*
G02X187348Y617441I1J4779D01*
G02X189022Y621074I4779J0D01*
G03X189092Y621226I-130J152D01*
G01Y621530D01*
G03X189022Y621682I-200J0D01*
G02Y628948I3105J3633D01*
G03X189092Y629100I-130J152D01*
G01Y629404D01*
G03X189022Y629556I-200J0D01*
G02X187348Y633189I3105J3633D01*
G01Y633191D01*
G02X192126Y637968I4778J-1D01*
G02X195759Y636293I-1J-4779D01*
G03X195911Y636223I152J130D01*
G01X196215D01*
G03X196367Y636293I0J200D01*
G02X200000Y637968I3634J-3104D01*
G02X201673Y637665I-2J-4779D01*
G01X201724Y637646D01*
X201828Y637664D01*
X202179Y637954D01*
X202216Y638055D01*
X202207Y638108D01*
G02X213541I5667J986D01*
G37*
G36*
G01X1476378Y637968D02*
G02X1480011Y636293I-1J-4779D01*
G03X1480163Y636223I152J130D01*
G01X1480467D01*
G03X1480619Y636293I0J200D01*
G02X1484252Y637968I3634J-3104D01*
G02X1489030Y633189I-1J-4779D01*
G02X1487356Y629556I-4779J0D01*
G03X1487286Y629404I130J-152D01*
G01Y629100D01*
G03X1487356Y628948I200J0D01*
G02Y621682I-3105J-3633D01*
G03X1487286Y621530I130J-152D01*
G01Y621226D01*
G03X1487356Y621074I200J0D01*
G02X1489030Y617441I-3105J-3633D01*
G01Y617439D01*
G02X1484252Y612662I-4778J1D01*
G02X1480619Y614337I1J4779D01*
G03X1480467Y614407I-152J-130D01*
G01X1480163D01*
G03X1480011Y614337I0J-200D01*
G02X1476378Y612662I-3634J3104D01*
G02X1471600Y617441I1J4779D01*
G02X1473274Y621074I4779J0D01*
G03X1473344Y621226I-130J152D01*
G01Y621530D01*
G03X1473274Y621682I-200J0D01*
G02X1472062Y623263I3103J3634D01*
G01X1472044Y623301D01*
X1471981Y623356D01*
X1471657Y623454D01*
G03X1471497Y623435I-58J-191D01*
G02X1465511I-2993J5030D01*
G03X1465351Y623454I-102J-172D01*
G01X1465027Y623356D01*
X1464964Y623301D01*
X1464946Y623263D01*
G02X1463734Y621682I-4315J2053D01*
G03X1463664Y621530I130J-152D01*
G01Y621226D01*
G03X1463734Y621074I200J0D01*
G02X1465408Y617441I-3105J-3633D01*
G01Y617439D01*
G02X1460630Y612662I-4778J1D01*
G02X1456997Y614337I1J4779D01*
G03X1456845Y614407I-152J-130D01*
G01X1456541D01*
G03X1456389Y614337I0J-200D01*
G02X1452756Y612662I-3634J3104D01*
G02X1447978Y617441I1J4779D01*
G02X1449652Y621074I4779J0D01*
G03X1449722Y621226I-130J152D01*
G01Y621530D01*
G03X1449652Y621682I-200J0D01*
G02Y628948I3105J3633D01*
G03X1449722Y629100I-130J152D01*
G01Y629404D01*
G03X1449652Y629556I-200J0D01*
G02X1447978Y633189I3105J3633D01*
G01Y633191D01*
G02X1452756Y637968I4778J-1D01*
G02X1456389Y636293I-1J-4779D01*
G03X1456541Y636223I152J130D01*
G01X1456845D01*
G03X1456997Y636293I0J200D01*
G02X1460630Y637968I3634J-3104D01*
G02X1465339Y634002I0J-4779D01*
G03X1465445Y633857I197J33D01*
G01X1465731Y633712D01*
G03X1465910Y633711I90J178D01*
G02X1471098I2594J-5246D01*
G01X1471141Y633690D01*
X1471234Y633691D01*
X1471563Y633857D01*
G03X1471669Y634002I-91J178D01*
G02X1476378Y637968I4709J-813D01*
G37*
G36*
G01X1424356Y633189D02*
Y633191D01*
G02X1429134Y637968I4778J-1D01*
G02X1432767Y636293I-1J-4779D01*
G03X1432919Y636223I152J130D01*
G01X1433223D01*
G03X1433375Y636293I0J200D01*
G02X1437008Y637968I3634J-3104D01*
G02X1441786Y633189I-1J-4779D01*
G02X1440112Y629556I-4779J0D01*
G03X1440042Y629404I130J-152D01*
G01Y629100D01*
G03X1440112Y628948I200J0D01*
G02Y621682I-3105J-3633D01*
G03X1440042Y621530I130J-152D01*
G01Y621226D01*
G03X1440112Y621074I200J0D01*
G02X1441786Y617441I-3105J-3633D01*
G01Y617439D01*
G02X1437008Y612662I-4778J1D01*
G02X1433375Y614337I1J4779D01*
G03X1433223Y614407I-152J-130D01*
G01X1432919D01*
G03X1432767Y614337I0J-200D01*
G02X1429134Y612662I-3634J3104D01*
G02X1424356Y617441I1J4779D01*
G02X1426030Y621074I4779J0D01*
G03X1426100Y621226I-130J152D01*
G01Y621530D01*
G03X1426030Y621682I-200J0D01*
G02Y628948I3105J3633D01*
G03X1426100Y629100I-130J152D01*
G01Y629404D01*
G03X1426030Y629556I-200J0D01*
G02X1424356Y633189I3105J3633D01*
G37*
G36*
G01X295276Y637968D02*
G02X298909Y636293I-1J-4779D01*
G03X299061Y636223I152J130D01*
G01X299365D01*
G03X299517Y636293I0J200D01*
G02X303150Y637968I3634J-3104D01*
G02X307928Y633189I-1J-4779D01*
G02X306254Y629556I-4779J0D01*
G03X306184Y629404I130J-152D01*
G01Y629100D01*
G03X306254Y628948I200J0D01*
G02Y621682I-3105J-3633D01*
G03X306184Y621530I130J-152D01*
G01Y621226D01*
G03X306254Y621074I200J0D01*
G02X307928Y617441I-3105J-3633D01*
G01Y617439D01*
G02X303150Y612662I-4778J1D01*
G02X299517Y614337I1J4779D01*
G03X299365Y614407I-152J-130D01*
G01X299061D01*
G03X298909Y614337I0J-200D01*
G02X295276Y612662I-3634J3104D01*
G02X290498Y617441I1J4779D01*
G02X292172Y621074I4779J0D01*
G03X292242Y621226I-130J152D01*
G01Y621530D01*
G03X292172Y621682I-200J0D01*
G02X290960Y623263I3103J3634D01*
G01X290942Y623301D01*
X290879Y623356D01*
X290555Y623454D01*
G03X290395Y623435I-58J-191D01*
G02X284409I-2993J5030D01*
G03X284249Y623454I-102J-172D01*
G01X283925Y623356D01*
X283862Y623301D01*
X283844Y623263D01*
G02X282632Y621682I-4315J2053D01*
G03X282562Y621530I130J-152D01*
G01Y621226D01*
G03X282632Y621074I200J0D01*
G02X284306Y617441I-3105J-3633D01*
G01Y617439D01*
G02X279528Y612662I-4778J1D01*
G02X275895Y614337I1J4779D01*
G03X275743Y614407I-152J-130D01*
G01X275439D01*
G03X275287Y614337I0J-200D01*
G02X271654Y612662I-3634J3104D01*
G02X266876Y617441I1J4779D01*
G02X268550Y621074I4779J0D01*
G03X268620Y621226I-130J152D01*
G01Y621530D01*
G03X268550Y621682I-200J0D01*
G02Y628948I3105J3633D01*
G03X268620Y629100I-130J152D01*
G01Y629404D01*
G03X268550Y629556I-200J0D01*
G02X266876Y633189I3105J3633D01*
G01Y633191D01*
G02X271654Y637968I4778J-1D01*
G02X275287Y636293I-1J-4779D01*
G03X275439Y636223I152J130D01*
G01X275743D01*
G03X275895Y636293I0J200D01*
G02X279528Y637968I3634J-3104D01*
G02X284237Y634002I0J-4779D01*
G03X284343Y633857I197J33D01*
G01X284629Y633712D01*
G03X284808Y633711I90J178D01*
G02X289996I2594J-5246D01*
G01X290039Y633690D01*
X290132Y633691D01*
X290461Y633857D01*
G03X290567Y634002I-91J178D01*
G02X295276Y637968I4709J-813D01*
G37*
G36*
G01X243254Y633189D02*
Y633191D01*
G02X248032Y637968I4778J-1D01*
G02X251665Y636293I-1J-4779D01*
G03X251817Y636223I152J130D01*
G01X252121D01*
G03X252273Y636293I0J200D01*
G02X255906Y637968I3634J-3104D01*
G02X260684Y633189I-1J-4779D01*
G02X259010Y629556I-4779J0D01*
G03X258940Y629404I130J-152D01*
G01Y629100D01*
G03X259010Y628948I200J0D01*
G02Y621682I-3105J-3633D01*
G03X258940Y621530I130J-152D01*
G01Y621226D01*
G03X259010Y621074I200J0D01*
G02X260684Y617441I-3105J-3633D01*
G01Y617439D01*
G02X255906Y612662I-4778J1D01*
G02X252273Y614337I1J4779D01*
G03X252121Y614407I-152J-130D01*
G01X251817D01*
G03X251665Y614337I0J-200D01*
G02X248032Y612662I-3634J3104D01*
G02X243254Y617441I1J4779D01*
G02X244928Y621074I4779J0D01*
G03X244998Y621226I-130J152D01*
G01Y621530D01*
G03X244928Y621682I-200J0D01*
G02Y628948I3105J3633D01*
G03X244998Y629100I-130J152D01*
G01Y629404D01*
G03X244928Y629556I-200J0D01*
G02X243254Y633189I3105J3633D01*
G37*
G36*
G01X1197534Y318912D02*
Y318914D01*
G02X1201037Y315410I3503J-1D01*
G01X1200968D01*
X1200964D01*
X1200920Y315411D01*
X1200838Y315374D01*
X1200608Y315101D01*
G03X1200565Y314934I153J-129D01*
G02X1200630Y314264I-3438J-672D01*
G01Y314262D01*
G02X1197127Y317766I-3503J1D01*
G01X1197196D01*
X1197200D01*
X1197244Y317765D01*
X1197326Y317802D01*
X1197556Y318075D01*
G03X1197599Y318242I-153J129D01*
G02X1197534Y318912I3438J672D01*
G37*
G36*
G01X1176200Y312998D02*
X1176198D01*
G02X1174781Y313298I1J3502D01*
G03X1174619I-81J-183D01*
G02X1173202Y312998I-1418J3202D01*
G01X1173200D01*
G02Y320002I0J3502D01*
G01X1173202D01*
G02X1174619Y319702I-1J-3502D01*
G03X1174781I81J183D01*
G02X1176198Y320002I1418J-3202D01*
G01X1176200D01*
G02Y312998I0J-3502D01*
G37*
G36*
G01X1304198Y309900D02*
G02X1304498Y311319I3502J1D01*
G03Y311481I-183J81D01*
G02X1304198Y312898I3202J1418D01*
G01Y312900D01*
G02X1307700Y316402I3502J0D01*
G01X1307702D01*
G02X1309119Y316102I-1J-3502D01*
G03X1309281I81J183D01*
G02X1310698Y316402I1418J-3202D01*
G01X1310700D01*
G02X1314149Y313511I0J-3503D01*
G03X1314311Y313349I197J35D01*
G02X1317149Y310511I-611J-3449D01*
G03X1317311Y310349I197J35D01*
G02X1320149Y307511I-611J-3449D01*
G03X1320311Y307349I197J35D01*
G02X1323202Y303900I-612J-3449D01*
G01Y303898D01*
G02X1322902Y302481I-3502J1D01*
G03Y302319I183J-81D01*
G02X1323202Y300902I-3202J-1418D01*
G01Y300900D01*
G02X1319700Y297398I-3502J0D01*
G01X1319698D01*
G02X1318281Y297698I1J3502D01*
G03X1318119I-81J-183D01*
G02X1316700Y297398I-1418J3202D01*
G02X1315281Y297698I-1J3502D01*
G03X1315119I-81J-183D01*
G02X1313700Y297398I-1418J3202D01*
G02X1312281Y297698I-1J3502D01*
G03X1312119I-81J-183D01*
G02X1310700Y297398I-1418J3202D01*
G02X1309281Y297698I-1J3502D01*
G03X1309119I-81J-183D01*
G02X1307702Y297398I-1418J3202D01*
G01X1307700D01*
G02X1304198Y300900I0J3502D01*
G01Y300902D01*
G02X1304498Y302319I3502J-1D01*
G03Y302481I-183J81D01*
G02X1304198Y303900I3202J1418D01*
G02X1304498Y305319I3502J1D01*
G03Y305481I-183J81D01*
G02X1304198Y306900I3202J1418D01*
G02X1304498Y308319I3502J1D01*
G03Y308481I-183J81D01*
G02X1304198Y309900I3202J1418D01*
G37*
G36*
G01X1106661Y304198D02*
X1106659D01*
G02X1105242Y304498I1J3502D01*
G03X1105080I-81J-183D01*
G02X1103663Y304198I-1418J3202D01*
G01X1103661D01*
G02Y311202I0J3502D01*
G01X1103663D01*
G02X1105080Y310902I-1J-3502D01*
G03X1105242I81J183D01*
G02X1106659Y311202I1418J-3202D01*
G01X1106661D01*
G02Y304198I0J-3502D01*
G37*
G36*
G01X565091Y299090D02*
G02Y306094I0J3502D01*
G01X565092D01*
G02X567440Y305190I0J-3502D01*
G01X567469Y305164D01*
X567540Y305137D01*
X567853Y305143D01*
G03X567989Y305201I-5J200D01*
G02X570442Y306204I2453J-2499D01*
G01X570443D01*
G02Y299200I0J-3502D01*
G01X570442D01*
G02X568094Y300104I0J3502D01*
G01X568065Y300130D01*
X567994Y300157D01*
X567681Y300151D01*
G03X567545Y300093I5J-200D01*
G02X565092Y299090I-2453J2499D01*
G01X565091D01*
G37*
G36*
G01X1840590Y300433D02*
Y300435D01*
G02X1846142Y305986I5552J-1D01*
G02X1851100Y302933I0J-5552D01*
G01X1851125Y302882D01*
X1851221Y302823D01*
X1851693D01*
X1851789Y302882D01*
X1851814Y302933D01*
G02X1856772Y305986I4958J-2499D01*
G02X1862324Y300433I-1J-5553D01*
G02X1859785Y295769I-5553J0D01*
G01X1859742Y295741D01*
X1859693Y295652D01*
Y295214D01*
X1859742Y295125D01*
X1859785Y295097D01*
G02Y285769I-3014J-4664D01*
G01X1859742Y285741D01*
X1859693Y285652D01*
Y285214D01*
X1859742Y285125D01*
X1859785Y285097D01*
G02Y275769I-3014J-4664D01*
G01X1859742Y275741D01*
X1859693Y275652D01*
Y275214D01*
X1859742Y275125D01*
X1859785Y275097D01*
G02X1862324Y270433I-3014J-4664D01*
G01Y270431D01*
G02X1856772Y264880I-5552J1D01*
G02X1851814Y267933I0J5552D01*
G01X1851789Y267984D01*
X1851693Y268043D01*
X1851221D01*
X1851125Y267984D01*
X1851100Y267933D01*
G02X1846142Y264880I-4958J2499D01*
G02X1840590Y270433I1J5553D01*
G02X1843129Y275097I5553J0D01*
G01X1843172Y275125D01*
X1843221Y275214D01*
Y275652D01*
X1843172Y275741D01*
X1843129Y275769D01*
G02Y285097I3014J4664D01*
G01X1843172Y285125D01*
X1843221Y285214D01*
Y285652D01*
X1843172Y285741D01*
X1843129Y285769D01*
G02Y295097I3014J4664D01*
G01X1843172Y295125D01*
X1843221Y295214D01*
Y295652D01*
X1843172Y295741D01*
X1843129Y295769D01*
G02X1840590Y300433I3014J4664D01*
G37*
G36*
G01X1199059Y290701D02*
X1198941D01*
G03X1198810Y290651I1J-200D01*
G02X1196500Y289782I-2309J2634D01*
G02Y296786I0J3502D01*
G02X1198810Y295917I1J-3503D01*
G03X1198941Y295867I132J150D01*
G01X1199059D01*
G03X1199190Y295917I-1J200D01*
G02X1201500Y296786I2309J-2634D01*
G02Y289782I0J-3502D01*
G02X1199190Y290651I-1J3503D01*
G03X1199059Y290701I-132J-150D01*
G37*
G36*
G01X568040Y289065D02*
Y289066D01*
G02X568410Y290633I3502J0D01*
G03X568398Y290832I-179J89D01*
G02X567822Y292757I2926J1924D01*
G02X574828I3503J0D01*
G02X574457Y291189I-3503J1D01*
G03X574469Y290990I179J-89D01*
G02X575044Y289068I-2928J-1923D01*
G01Y289065D01*
G02X568040I-3502J0D01*
G37*
G36*
G01X1055300Y287398D02*
X1055297D01*
G02X1053834Y287719I2J3502D01*
G03X1053666I-84J-182D01*
G02X1052203Y287398I-1465J3181D01*
G01X1052200D01*
G02Y294402I0J3502D01*
G01X1052203D01*
G02X1053666Y294081I-2J-3502D01*
G03X1053834I84J182D01*
G02X1055297Y294402I1465J-3181D01*
G01X1055300D01*
G02Y287398I0J-3502D01*
G37*
G36*
G01X448738Y293502D02*
G02X450157Y293202I1J-3502D01*
G03X450319I81J183D01*
G02X451738Y293502I1418J-3202D01*
G02X453157Y293202I1J-3502D01*
G03X453319I81J183D01*
G02X454736Y293502I1418J-3202D01*
G01X454738D01*
G02X458240Y290000I0J-3502D01*
G01Y289998D01*
G02X457940Y288581I-3502J1D01*
G03Y288419I183J-81D01*
G02X458240Y287000I-3202J-1418D01*
G02X457940Y285581I-3502J-1D01*
G03Y285419I183J-81D01*
G02X458240Y284000I-3202J-1418D01*
G02X457940Y282581I-3502J-1D01*
G03Y282419I183J-81D01*
G02X458240Y281000I-3202J-1418D01*
G02X457940Y279581I-3502J-1D01*
G03Y279419I183J-81D01*
G02X458240Y278002I-3202J-1418D01*
G01Y278000D01*
G02X454738Y274498I-3502J0D01*
G01X454736D01*
G02X453319Y274798I1J3502D01*
G03X453157I-81J-183D01*
G02X451738Y274498I-1418J3202D01*
G02X450319Y274798I-1J3502D01*
G03X450157I-81J-183D01*
G02X448738Y274498I-1418J3202D01*
G02X447319Y274798I-1J3502D01*
G03X447157I-81J-183D01*
G02X445738Y274498I-1418J3202D01*
G02X444319Y274798I-1J3502D01*
G03X444157I-81J-183D01*
G02X442740Y274498I-1418J3202D01*
G01X442738D01*
G02X439236Y278000I0J3502D01*
G01Y278002D01*
G02X439536Y279419I3502J-1D01*
G03Y279581I-183J81D01*
G02X439236Y281000I3202J1418D01*
G02X439536Y282419I3502J1D01*
G03Y282581I-183J81D01*
G02X439236Y284000I3202J1418D01*
G02X439536Y285419I3502J1D01*
G03Y285581I-183J81D01*
G02X439236Y287000I3202J1418D01*
G02X439536Y288419I3502J1D01*
G03Y288581I-183J81D01*
G02X439236Y289998I3202J1418D01*
G01Y290000D01*
G02X442738Y293502I3502J0D01*
G01X442740D01*
G02X444157Y293202I-1J-3502D01*
G03X444319I81J183D01*
G02X445738Y293502I1418J-3202D01*
G02X447157Y293202I1J-3502D01*
G03X447319I81J183D01*
G02X448738Y293502I1418J-3202D01*
G37*
G36*
G01X586796Y282890D02*
G02X593800I3502J0D01*
G02X592588Y280240I-3503J0D01*
G03X592519Y280089I131J-151D01*
G01Y279785D01*
G03X592588Y279634I200J0D01*
G02X593800Y276984I-2291J-2650D01*
G02X586796I-3502J0D01*
G02X588008Y279634I3503J0D01*
G03X588077Y279785I-131J151D01*
G01Y280089D01*
G03X588008Y280240I-200J0D01*
G02X586796Y282890I2291J2650D01*
G37*
G36*
G01X1059300Y276098D02*
X1059298D01*
G02X1057550Y276566I1J3502D01*
G03X1057350I-100J-173D01*
G02X1055602Y276098I-1749J3034D01*
G01X1055600D01*
G02Y283102I0J3502D01*
G01X1055602D01*
G02X1057350Y282634I-1J-3502D01*
G03X1057550I100J173D01*
G02X1059298Y283102I1749J-3034D01*
G01X1059300D01*
G02Y276098I0J-3502D01*
G37*
G36*
G01X715982Y278980D02*
G02X722986I3502J0D01*
G02X720657Y275680I-3502J0D01*
G01X720615Y275665D01*
X720553Y275604D01*
X720430Y275276D01*
G03X720442Y275108I187J-71D01*
G02X720886Y273403I-3058J-1707D01*
G01Y273400D01*
G02X713882I-3502J0D01*
G02X716211Y276700I3502J0D01*
G01X716253Y276715D01*
X716315Y276776D01*
X716438Y277104D01*
G03X716426Y277272I-187J71D01*
G02X715982Y278977I3058J1707D01*
G01Y278980D01*
G37*
G36*
G01X706684Y268898D02*
X706682D01*
G02X704934Y269366I1J3502D01*
G03X704734I-100J-173D01*
G02X702986Y268898I-1749J3034D01*
G01X702984D01*
G02Y275902I0J3502D01*
G01X702986D01*
G02X704734Y275434I-1J-3502D01*
G03X704934I100J173D01*
G02X706682Y275902I1749J-3034D01*
G01X706684D01*
G02Y268898I0J-3502D01*
G37*
G36*
G01X730600Y266498D02*
X730598D01*
G02X729181Y266798I1J3502D01*
G03X729019I-81J-183D01*
G02X727602Y266498I-1418J3202D01*
G01X727600D01*
G02Y273502I0J3502D01*
G01X727602D01*
G02X729019Y273202I-1J-3502D01*
G03X729181I81J183D01*
G02X730598Y273502I1418J-3202D01*
G01X730600D01*
G02Y266498I0J-3502D01*
G37*
G36*
G01X1313700Y272002D02*
G02X1315119Y271702I1J-3502D01*
G03X1315281I81J183D01*
G02X1316700Y272002I1418J-3202D01*
G02X1318119Y271702I1J-3502D01*
G03X1318281I81J183D01*
G02X1319698Y272002I1418J-3202D01*
G01X1319700D01*
G02X1323202Y268500I0J-3502D01*
G01Y268498D01*
G02X1322902Y267081I-3502J1D01*
G03Y266919I183J-81D01*
G02X1323202Y265500I-3202J-1418D01*
G02X1322902Y264081I-3502J-1D01*
G03Y263919I183J-81D01*
G02X1323202Y262500I-3202J-1418D01*
G02X1322902Y261081I-3502J-1D01*
G03Y260919I183J-81D01*
G02X1323202Y259500I-3202J-1418D01*
G02X1322902Y258081I-3502J-1D01*
G03Y257919I183J-81D01*
G02X1323202Y256502I-3202J-1418D01*
G01Y256500D01*
G02X1319700Y252998I-3502J0D01*
G01X1319698D01*
G02X1318281Y253298I1J3502D01*
G03X1318119I-81J-183D01*
G02X1316700Y252998I-1418J3202D01*
G02X1315281Y253298I-1J3502D01*
G03X1315119I-81J-183D01*
G02X1313700Y252998I-1418J3202D01*
G02X1312281Y253298I-1J3502D01*
G03X1312119I-81J-183D01*
G02X1310700Y252998I-1418J3202D01*
G02X1309281Y253298I-1J3502D01*
G03X1309119I-81J-183D01*
G02X1307702Y252998I-1418J3202D01*
G01X1307700D01*
G02X1304198Y256500I0J3502D01*
G01Y256502D01*
G02X1304498Y257919I3502J-1D01*
G03Y258081I-183J81D01*
G02X1304198Y259500I3202J1418D01*
G02X1304498Y260919I3502J1D01*
G03Y261081I-183J81D01*
G02X1304198Y262500I3202J1418D01*
G02X1304498Y263919I3502J1D01*
G03Y264081I-183J81D01*
G02X1304198Y265500I3202J1418D01*
G02X1304498Y266919I3502J1D01*
G03Y267081I-183J81D01*
G02X1304198Y268498I3202J1418D01*
G01Y268500D01*
G02X1307700Y272002I3502J0D01*
G01X1307702D01*
G02X1309119Y271702I-1J-3502D01*
G03X1309281I81J183D01*
G02X1310700Y272002I1418J-3202D01*
G02X1312119Y271702I1J-3502D01*
G03X1312281I81J183D01*
G02X1313700Y272002I1418J-3202D01*
G37*
G36*
G01X1059300Y264998D02*
X1059298D01*
G02X1057550Y265466I1J3502D01*
G03X1057350I-100J-173D01*
G02X1055602Y264998I-1749J3034D01*
G01X1055600D01*
G02Y272002I0J3502D01*
G01X1055602D01*
G02X1057350Y271534I-1J-3502D01*
G03X1057550I100J173D01*
G02X1059298Y272002I1749J-3034D01*
G01X1059300D01*
G02Y264998I0J-3502D01*
G37*
G36*
G01X710084Y257598D02*
X710081D01*
G02X708618Y257919I2J3502D01*
G03X708450I-84J-182D01*
G02X706987Y257598I-1465J3181D01*
G01X706984D01*
G02Y264602I0J3502D01*
G01X706987D01*
G02X708450Y264281I-2J-3502D01*
G03X708618I84J182D01*
G02X710081Y264602I1465J-3181D01*
G01X710084D01*
G02Y257598I0J-3502D01*
G37*
G36*
G01X448738Y249102D02*
G02X450157Y248802I1J-3502D01*
G03X450319I81J183D01*
G02X451738Y249102I1418J-3202D01*
G02X453157Y248802I1J-3502D01*
G03X453319I81J183D01*
G02X454736Y249102I1418J-3202D01*
G01X454738D01*
G02X458240Y245600I0J-3502D01*
G01Y245598D01*
G02X457940Y244181I-3502J1D01*
G03Y244019I183J-81D01*
G02X458240Y242600I-3202J-1418D01*
G02X457940Y241181I-3502J-1D01*
G03Y241019I183J-81D01*
G02X458240Y239600I-3202J-1418D01*
G02X457940Y238181I-3502J-1D01*
G03Y238019I183J-81D01*
G02X458240Y236600I-3202J-1418D01*
G02X457940Y235181I-3502J-1D01*
G03Y235019I183J-81D01*
G02X458240Y233602I-3202J-1418D01*
G01Y233600D01*
G02X454738Y230098I-3502J0D01*
G01X454736D01*
G02X453319Y230398I1J3502D01*
G03X453157I-81J-183D01*
G02X451738Y230098I-1418J3202D01*
G02X450319Y230398I-1J3502D01*
G03X450157I-81J-183D01*
G02X448738Y230098I-1418J3202D01*
G02X447319Y230398I-1J3502D01*
G03X447157I-81J-183D01*
G02X445738Y230098I-1418J3202D01*
G02X444319Y230398I-1J3502D01*
G03X444157I-81J-183D01*
G02X442740Y230098I-1418J3202D01*
G01X442738D01*
G02X439236Y233600I0J3502D01*
G01Y233602D01*
G02X439536Y235019I3502J-1D01*
G03Y235181I-183J81D01*
G02X439236Y236600I3202J1418D01*
G02X439536Y238019I3502J1D01*
G03Y238181I-183J81D01*
G02X439236Y239600I3202J1418D01*
G02X439536Y241019I3502J1D01*
G03Y241181I-183J81D01*
G02X439236Y242600I3202J1418D01*
G02X439536Y244019I3502J1D01*
G03Y244181I-183J81D01*
G02X439236Y245598I3202J1418D01*
G01Y245600D01*
G02X442738Y249102I3502J0D01*
G01X442740D01*
G02X444157Y248802I-1J-3502D01*
G03X444319I81J183D01*
G02X445738Y249102I1418J-3202D01*
G02X447157Y248802I1J-3502D01*
G03X447319I81J183D01*
G02X448738Y249102I1418J-3202D01*
G37*
G36*
G01X658600Y234198D02*
X658598D01*
G02X657181Y234498I1J3502D01*
G03X657019I-81J-183D01*
G02X655602Y234198I-1418J3202D01*
G01X655600D01*
G02Y241202I0J3502D01*
G01X655602D01*
G02X657019Y240902I-1J-3502D01*
G03X657181I81J183D01*
G02X658598Y241202I1418J-3202D01*
G01X658600D01*
G02Y234198I0J-3502D01*
G37*
G36*
G01X1070600Y231502D02*
G02X1072019Y231202I1J-3502D01*
G03X1072181I81J183D01*
G02X1073598Y231502I1418J-3202D01*
G01X1073600D01*
G02Y224498I0J-3502D01*
G01X1073598D01*
G02X1072181Y224798I1J3502D01*
G03X1072019I-81J-183D01*
G02X1070600Y224498I-1418J3202D01*
G02X1067907Y225760I-1J3502D01*
G01X1067879Y225794D01*
X1067799Y225832D01*
X1067401D01*
X1067321Y225794D01*
X1067293Y225760D01*
G02X1064600Y224498I-2692J2240D01*
G02X1063181Y224798I-1J3502D01*
G03X1063019I-81J-183D01*
G02X1061602Y224498I-1418J3202D01*
G01X1061600D01*
G02Y231502I0J3502D01*
G01X1061602D01*
G02X1063019Y231202I-1J-3502D01*
G03X1063181I81J183D01*
G02X1064600Y231502I1418J-3202D01*
G02X1067293Y230240I1J-3502D01*
G01X1067321Y230206D01*
X1067401Y230168D01*
X1067799D01*
X1067879Y230206D01*
X1067907Y230240D01*
G02X1070600Y231502I2692J-2240D01*
G37*
G36*
G01X1313700Y227602D02*
G02X1315119Y227302I1J-3502D01*
G03X1315281I81J183D01*
G02X1316700Y227602I1418J-3202D01*
G02X1318119Y227302I1J-3502D01*
G03X1318281I81J183D01*
G02X1319698Y227602I1418J-3202D01*
G01X1319700D01*
G02X1323202Y224100I0J-3502D01*
G01Y224098D01*
G02X1322902Y222681I-3502J1D01*
G03Y222519I183J-81D01*
G02X1323202Y221100I-3202J-1418D01*
G02X1322902Y219681I-3502J-1D01*
G03Y219519I183J-81D01*
G02X1323202Y218100I-3202J-1418D01*
G02X1322902Y216681I-3502J-1D01*
G03Y216519I183J-81D01*
G02X1323202Y215100I-3202J-1418D01*
G02X1322902Y213681I-3502J-1D01*
G03Y213519I183J-81D01*
G02X1323202Y212102I-3202J-1418D01*
G01Y212100D01*
G02X1319700Y208598I-3502J0D01*
G01X1319698D01*
G02X1318281Y208898I1J3502D01*
G03X1318119I-81J-183D01*
G02X1316700Y208598I-1418J3202D01*
G02X1315281Y208898I-1J3502D01*
G03X1315119I-81J-183D01*
G02X1313700Y208598I-1418J3202D01*
G02X1312281Y208898I-1J3502D01*
G03X1312119I-81J-183D01*
G02X1310700Y208598I-1418J3202D01*
G02X1309281Y208898I-1J3502D01*
G03X1309119I-81J-183D01*
G02X1307702Y208598I-1418J3202D01*
G01X1307700D01*
G02X1304198Y212100I0J3502D01*
G01Y212102D01*
G02X1304498Y213519I3502J-1D01*
G03Y213681I-183J81D01*
G02X1304198Y215100I3202J1418D01*
G02X1304498Y216519I3502J1D01*
G03Y216681I-183J81D01*
G02X1304198Y218100I3202J1418D01*
G02X1304498Y219519I3502J1D01*
G03Y219681I-183J81D01*
G02X1304198Y221100I3202J1418D01*
G02X1304498Y222519I3502J1D01*
G03Y222681I-183J81D01*
G02X1304198Y224098I3202J1418D01*
G01Y224100D01*
G02X1307700Y227602I3502J0D01*
G01X1307702D01*
G02X1309119Y227302I-1J-3502D01*
G03X1309281I81J183D01*
G02X1310700Y227602I1418J-3202D01*
G02X1312119Y227302I1J-3502D01*
G03X1312281I81J183D01*
G02X1313700Y227602I1418J-3202D01*
G37*
G36*
G01X448738Y204702D02*
G02X450157Y204402I1J-3502D01*
G03X450319I81J183D01*
G02X451738Y204702I1418J-3202D01*
G02X453157Y204402I1J-3502D01*
G03X453319I81J183D01*
G02X454736Y204702I1418J-3202D01*
G01X454738D01*
G02X458240Y201200I0J-3502D01*
G01Y201198D01*
G02X457940Y199781I-3502J1D01*
G03Y199619I183J-81D01*
G02X458240Y198200I-3202J-1418D01*
G02X457940Y196781I-3502J-1D01*
G03Y196619I183J-81D01*
G02X458240Y195200I-3202J-1418D01*
G02X457940Y193781I-3502J-1D01*
G03Y193619I183J-81D01*
G02X458240Y192200I-3202J-1418D01*
G02X457940Y190781I-3502J-1D01*
G03Y190619I183J-81D01*
G02X458240Y189202I-3202J-1418D01*
G01Y189200D01*
G02X454738Y185698I-3502J0D01*
G01X454736D01*
G02X453319Y185998I1J3502D01*
G03X453157I-81J-183D01*
G02X451738Y185698I-1418J3202D01*
G02X450319Y185998I-1J3502D01*
G03X450157I-81J-183D01*
G02X448738Y185698I-1418J3202D01*
G02X447319Y185998I-1J3502D01*
G03X447157I-81J-183D01*
G02X445738Y185698I-1418J3202D01*
G02X444319Y185998I-1J3502D01*
G03X444157I-81J-183D01*
G02X442740Y185698I-1418J3202D01*
G01X442738D01*
G02X439236Y189200I0J3502D01*
G01Y189202D01*
G02X439536Y190619I3502J-1D01*
G03Y190781I-183J81D01*
G02X439236Y192200I3202J1418D01*
G02X439536Y193619I3502J1D01*
G03Y193781I-183J81D01*
G02X439236Y195200I3202J1418D01*
G02X439536Y196619I3502J1D01*
G03Y196781I-183J81D01*
G02X439236Y198200I3202J1418D01*
G02X439536Y199619I3502J1D01*
G03Y199781I-183J81D01*
G02X439236Y201198I3202J1418D01*
G01Y201200D01*
G02X442738Y204702I3502J0D01*
G01X442740D01*
G02X444157Y204402I-1J-3502D01*
G03X444319I81J183D01*
G02X445738Y204702I1418J-3202D01*
G02X447157Y204402I1J-3502D01*
G03X447319I81J183D01*
G02X448738Y204702I1418J-3202D01*
G37*
G36*
G01X1307700Y183202D02*
X1307702D01*
G02X1309119Y182902I-1J-3502D01*
G03X1309281I81J183D01*
G02X1310700Y183202I1418J-3202D01*
G02X1312119Y182902I1J-3502D01*
G03X1312281I81J183D01*
G02X1313698Y183202I1418J-3202D01*
G01X1313700D01*
G02X1317149Y180311I0J-3503D01*
G03X1317311Y180149I197J35D01*
G02X1318119Y179902I-612J-3449D01*
G03X1318281I81J183D01*
G02X1319698Y180202I1418J-3202D01*
G01X1319700D01*
G02X1323202Y176700I0J-3502D01*
G01Y176698D01*
G02X1322902Y175281I-3502J1D01*
G03Y175119I183J-81D01*
G02X1323202Y173700I-3202J-1418D01*
G02X1322902Y172281I-3502J-1D01*
G03Y172119I183J-81D01*
G02X1323202Y170700I-3202J-1418D01*
G02X1322902Y169281I-3502J-1D01*
G03Y169119I183J-81D01*
G02X1323202Y167702I-3202J-1418D01*
G01Y167700D01*
G02X1319700Y164198I-3502J0D01*
G01X1319698D01*
G02X1318281Y164498I1J3502D01*
G03X1318119I-81J-183D01*
G02X1316700Y164198I-1418J3202D01*
G02X1315281Y164498I-1J3502D01*
G03X1315119I-81J-183D01*
G02X1313700Y164198I-1418J3202D01*
G02X1312281Y164498I-1J3502D01*
G03X1312119I-81J-183D01*
G02X1310700Y164198I-1418J3202D01*
G02X1309281Y164498I-1J3502D01*
G03X1309119I-81J-183D01*
G02X1307702Y164198I-1418J3202D01*
G01X1307700D01*
G02X1304198Y167700I0J3502D01*
G01Y167702D01*
G02X1304498Y169119I3502J-1D01*
G03Y169281I-183J81D01*
G02X1304198Y170700I3202J1418D01*
G02X1304498Y172119I3502J1D01*
G03Y172281I-183J81D01*
G02X1304198Y173700I3202J1418D01*
G02X1304498Y175119I3502J1D01*
G03Y175281I-183J81D01*
G02X1304198Y176700I3202J1418D01*
G02X1304498Y178119I3502J1D01*
G03Y178281I-183J81D01*
G02X1304198Y179698I3202J1418D01*
G01Y179700D01*
G02X1307700Y183202I3502J0D01*
G37*
G36*
G01X448738Y160302D02*
G02X450157Y160002I1J-3502D01*
G03X450319I81J183D01*
G02X451738Y160302I1418J-3202D01*
G02X453157Y160002I1J-3502D01*
G03X453319I81J183D01*
G02X454736Y160302I1418J-3202D01*
G01X454738D01*
G02X458240Y156800I0J-3502D01*
G01Y156798D01*
G02X457940Y155381I-3502J1D01*
G03Y155219I183J-81D01*
G02X458240Y153800I-3202J-1418D01*
G02X457940Y152381I-3502J-1D01*
G03Y152219I183J-81D01*
G02X458240Y150800I-3202J-1418D01*
G02X457940Y149381I-3502J-1D01*
G03Y149219I183J-81D01*
G02X458240Y147800I-3202J-1418D01*
G02X457940Y146381I-3502J-1D01*
G03Y146219I183J-81D01*
G02X458240Y144802I-3202J-1418D01*
G01Y144800D01*
G02X454738Y141298I-3502J0D01*
G01X454736D01*
G02X453319Y141598I1J3502D01*
G03X453157I-81J-183D01*
G02X451738Y141298I-1418J3202D01*
G02X450319Y141598I-1J3502D01*
G03X450157I-81J-183D01*
G02X448738Y141298I-1418J3202D01*
G02X447319Y141598I-1J3502D01*
G03X447157I-81J-183D01*
G02X445738Y141298I-1418J3202D01*
G02X444319Y141598I-1J3502D01*
G03X444157I-81J-183D01*
G02X442740Y141298I-1418J3202D01*
G01X442738D01*
G02X439236Y144800I0J3502D01*
G01Y144802D01*
G02X439536Y146219I3502J-1D01*
G03Y146381I-183J81D01*
G02X439236Y147800I3202J1418D01*
G02X439536Y149219I3502J1D01*
G03Y149381I-183J81D01*
G02X439236Y150800I3202J1418D01*
G02X439536Y152219I3502J1D01*
G03Y152381I-183J81D01*
G02X439236Y153800I3202J1418D01*
G02X439536Y155219I3502J1D01*
G03Y155381I-183J81D01*
G02X439236Y156798I3202J1418D01*
G01Y156800D01*
G02X442738Y160302I3502J0D01*
G01X442740D01*
G02X444157Y160002I-1J-3502D01*
G03X444319I81J183D01*
G02X445738Y160302I1418J-3202D01*
G02X447157Y160002I1J-3502D01*
G03X447319I81J183D01*
G02X448738Y160302I1418J-3202D01*
G37*
G36*
G01X1313700Y138802D02*
G02X1315119Y138502I1J-3502D01*
G03X1315281I81J183D01*
G02X1316700Y138802I1418J-3202D01*
G02X1318119Y138502I1J-3502D01*
G03X1318281I81J183D01*
G02X1319698Y138802I1418J-3202D01*
G01X1319700D01*
G02X1323202Y135300I0J-3502D01*
G01Y135298D01*
G02X1322902Y133881I-3502J1D01*
G03Y133719I183J-81D01*
G02X1323202Y132300I-3202J-1418D01*
G02X1322902Y130881I-3502J-1D01*
G03Y130719I183J-81D01*
G02X1323202Y129300I-3202J-1418D01*
G02X1322902Y127881I-3502J-1D01*
G03Y127719I183J-81D01*
G02X1323202Y126300I-3202J-1418D01*
G02X1322902Y124881I-3502J-1D01*
G03Y124719I183J-81D01*
G02X1323202Y123302I-3202J-1418D01*
G01Y123300D01*
G02X1319700Y119798I-3502J0D01*
G01X1319698D01*
G02X1318281Y120098I1J3502D01*
G03X1318119I-81J-183D01*
G02X1316700Y119798I-1418J3202D01*
G02X1315281Y120098I-1J3502D01*
G03X1315119I-81J-183D01*
G02X1313700Y119798I-1418J3202D01*
G02X1312281Y120098I-1J3502D01*
G03X1312119I-81J-183D01*
G02X1310700Y119798I-1418J3202D01*
G02X1309281Y120098I-1J3502D01*
G03X1309119I-81J-183D01*
G02X1307702Y119798I-1418J3202D01*
G01X1307700D01*
G02X1304198Y123300I0J3502D01*
G01Y123302D01*
G02X1304498Y124719I3502J-1D01*
G03Y124881I-183J81D01*
G02X1304198Y126300I3202J1418D01*
G02X1304498Y127719I3502J1D01*
G03Y127881I-183J81D01*
G02X1304198Y129300I3202J1418D01*
G02X1304498Y130719I3502J1D01*
G03Y130881I-183J81D01*
G02X1304198Y132300I3202J1418D01*
G02X1304498Y133719I3502J1D01*
G03Y133881I-183J81D01*
G02X1304198Y135298I3202J1418D01*
G01Y135300D01*
G02X1307700Y138802I3502J0D01*
G01X1307702D01*
G02X1309119Y138502I-1J-3502D01*
G03X1309281I81J183D01*
G02X1310700Y138802I1418J-3202D01*
G02X1312119Y138502I1J-3502D01*
G03X1312281I81J183D01*
G02X1313700Y138802I1418J-3202D01*
G37*
G36*
G01X448738Y115902D02*
G02X450157Y115602I1J-3502D01*
G03X450319I81J183D01*
G02X451738Y115902I1418J-3202D01*
G02X453157Y115602I1J-3502D01*
G03X453319I81J183D01*
G02X454736Y115902I1418J-3202D01*
G01X454738D01*
G02X458240Y112400I0J-3502D01*
G01Y112398D01*
G02X457940Y110981I-3502J1D01*
G03Y110819I183J-81D01*
G02X458240Y109400I-3202J-1418D01*
G02X457940Y107981I-3502J-1D01*
G03Y107819I183J-81D01*
G02X458240Y106400I-3202J-1418D01*
G02X457940Y104981I-3502J-1D01*
G03Y104819I183J-81D01*
G02X458240Y103400I-3202J-1418D01*
G02X457940Y101981I-3502J-1D01*
G03Y101819I183J-81D01*
G02X458240Y100402I-3202J-1418D01*
G01Y100400D01*
G02X454738Y96898I-3502J0D01*
G01X454736D01*
G02X453319Y97198I1J3502D01*
G03X453157I-81J-183D01*
G02X451738Y96898I-1418J3202D01*
G02X450319Y97198I-1J3502D01*
G03X450157I-81J-183D01*
G02X448738Y96898I-1418J3202D01*
G02X447319Y97198I-1J3502D01*
G03X447157I-81J-183D01*
G02X445738Y96898I-1418J3202D01*
G02X444319Y97198I-1J3502D01*
G03X444157I-81J-183D01*
G02X442740Y96898I-1418J3202D01*
G01X442738D01*
G02X439236Y100400I0J3502D01*
G01Y100402D01*
G02X439536Y101819I3502J-1D01*
G03Y101981I-183J81D01*
G02X439236Y103400I3202J1418D01*
G02X439536Y104819I3502J1D01*
G03Y104981I-183J81D01*
G02X439236Y106400I3202J1418D01*
G02X439536Y107819I3502J1D01*
G03Y107981I-183J81D01*
G02X439236Y109400I3202J1418D01*
G02X439536Y110819I3502J1D01*
G03Y110981I-183J81D01*
G02X439236Y112398I3202J1418D01*
G01Y112400D01*
G02X442738Y115902I3502J0D01*
G01X442740D01*
G02X444157Y115602I-1J-3502D01*
G03X444319I81J183D01*
G02X445738Y115902I1418J-3202D01*
G02X447157Y115602I1J-3502D01*
G03X447319I81J183D01*
G02X448738Y115902I1418J-3202D01*
G37*
G36*
G01X1313700Y94402D02*
G02X1315119Y94102I1J-3502D01*
G03X1315281I81J183D01*
G02X1316700Y94402I1418J-3202D01*
G02X1318119Y94102I1J-3502D01*
G03X1318281I81J183D01*
G02X1319698Y94402I1418J-3202D01*
G01X1319700D01*
G02X1323202Y90900I0J-3502D01*
G01Y90898D01*
G02X1322902Y89481I-3502J1D01*
G03Y89319I183J-81D01*
G02X1323202Y87900I-3202J-1418D01*
G02X1322902Y86481I-3502J-1D01*
G03Y86319I183J-81D01*
G02X1323202Y84900I-3202J-1418D01*
G02X1322902Y83481I-3502J-1D01*
G03Y83319I183J-81D01*
G02X1323202Y81900I-3202J-1418D01*
G02X1322902Y80481I-3502J-1D01*
G03Y80319I183J-81D01*
G02X1323202Y78902I-3202J-1418D01*
G01Y78900D01*
G02X1319700Y75398I-3502J0D01*
G01X1319698D01*
G02X1318281Y75698I1J3502D01*
G03X1318119I-81J-183D01*
G02X1316700Y75398I-1418J3202D01*
G02X1315281Y75698I-1J3502D01*
G03X1315119I-81J-183D01*
G02X1313700Y75398I-1418J3202D01*
G02X1312281Y75698I-1J3502D01*
G03X1312119I-81J-183D01*
G02X1310700Y75398I-1418J3202D01*
G02X1309281Y75698I-1J3502D01*
G03X1309119I-81J-183D01*
G02X1307702Y75398I-1418J3202D01*
G01X1307700D01*
G02X1304198Y78900I0J3502D01*
G01Y78902D01*
G02X1304498Y80319I3502J-1D01*
G03Y80481I-183J81D01*
G02X1304198Y81900I3202J1418D01*
G02X1304498Y83319I3502J1D01*
G03Y83481I-183J81D01*
G02X1304198Y84900I3202J1418D01*
G02X1304498Y86319I3502J1D01*
G03Y86481I-183J81D01*
G02X1304198Y87900I3202J1418D01*
G02X1304498Y89319I3502J1D01*
G03Y89481I-183J81D01*
G02X1304198Y90898I3202J1418D01*
G01Y90900D01*
G02X1307700Y94402I3502J0D01*
G01X1307702D01*
G02X1309119Y94102I-1J-3502D01*
G03X1309281I81J183D01*
G02X1310700Y94402I1418J-3202D01*
G02X1312119Y94102I1J-3502D01*
G03X1312281I81J183D01*
G02X1313700Y94402I1418J-3202D01*
G37*
G36*
G01X448738Y71502D02*
G02X450157Y71202I1J-3502D01*
G03X450319I81J183D01*
G02X451738Y71502I1418J-3202D01*
G02X453157Y71202I1J-3502D01*
G03X453319I81J183D01*
G02X454736Y71502I1418J-3202D01*
G01X454738D01*
G02X458240Y68000I0J-3502D01*
G01Y67998D01*
G02X457940Y66581I-3502J1D01*
G03Y66419I183J-81D01*
G02X458240Y65000I-3202J-1418D01*
G02X457940Y63581I-3502J-1D01*
G03Y63419I183J-81D01*
G02X458240Y62000I-3202J-1418D01*
G02X457940Y60581I-3502J-1D01*
G03Y60419I183J-81D01*
G02X458240Y59000I-3202J-1418D01*
G02X457940Y57581I-3502J-1D01*
G03Y57419I183J-81D01*
G02X458240Y56002I-3202J-1418D01*
G01Y56000D01*
G02X454738Y52498I-3502J0D01*
G01X454736D01*
G02X453319Y52798I1J3502D01*
G03X453157I-81J-183D01*
G02X451738Y52498I-1418J3202D01*
G02X450319Y52798I-1J3502D01*
G03X450157I-81J-183D01*
G02X448738Y52498I-1418J3202D01*
G02X447319Y52798I-1J3502D01*
G03X447157I-81J-183D01*
G02X445738Y52498I-1418J3202D01*
G02X444319Y52798I-1J3502D01*
G03X444157I-81J-183D01*
G02X442740Y52498I-1418J3202D01*
G01X442738D01*
G02X439236Y56000I0J3502D01*
G01Y56002D01*
G02X439536Y57419I3502J-1D01*
G03Y57581I-183J81D01*
G02X439236Y59000I3202J1418D01*
G02X439536Y60419I3502J1D01*
G03Y60581I-183J81D01*
G02X439236Y62000I3202J1418D01*
G02X439536Y63419I3502J1D01*
G03Y63581I-183J81D01*
G02X439236Y65000I3202J1418D01*
G02X439536Y66419I3502J1D01*
G03Y66581I-183J81D01*
G02X439236Y67998I3202J1418D01*
G01Y68000D01*
G02X442738Y71502I3502J0D01*
G01X442740D01*
G02X444157Y71202I-1J-3502D01*
G03X444319I81J183D01*
G02X445738Y71502I1418J-3202D01*
G02X447157Y71202I1J-3502D01*
G03X447319I81J183D01*
G02X448738Y71502I1418J-3202D01*
G37*
G36*
G01X1406230Y24578D02*
G02X1407649Y24278I1J-3502D01*
G03X1407811I81J183D01*
G02X1409230Y24578I1418J-3202D01*
G02X1410649Y24278I1J-3502D01*
G03X1410811I81J183D01*
G02X1412228Y24578I1418J-3202D01*
G01X1412230D01*
G02X1415732Y21076I0J-3502D01*
G01Y21074D01*
G02X1415432Y19657I-3502J1D01*
G03Y19495I183J-81D01*
G02X1415732Y18076I-3202J-1418D01*
G02X1415432Y16657I-3502J-1D01*
G03Y16495I183J-81D01*
G02X1415732Y15078I-3202J-1418D01*
G01Y15076D01*
G02X1412230Y11574I-3502J0D01*
G01X1412228D01*
G02X1410811Y11874I1J3502D01*
G03X1410649I-81J-183D01*
G02X1409230Y11574I-1418J3202D01*
G02X1407811Y11874I-1J3502D01*
G03X1407649I-81J-183D01*
G02X1406230Y11574I-1418J3202D01*
G02X1404811Y11874I-1J3502D01*
G03X1404649I-81J-183D01*
G02X1403230Y11574I-1418J3202D01*
G02X1401811Y11874I-1J3502D01*
G03X1401649I-81J-183D01*
G02X1400230Y11574I-1418J3202D01*
G02X1398811Y11874I-1J3502D01*
G03X1398649I-81J-183D01*
G02X1397232Y11574I-1418J3202D01*
G01X1397230D01*
G02X1393728Y15076I0J3502D01*
G01Y15078D01*
G02X1394028Y16495I3502J-1D01*
G03Y16657I-183J81D01*
G02X1393728Y18076I3202J1418D01*
G02X1394028Y19495I3502J1D01*
G03Y19657I-183J81D01*
G02X1393728Y21074I3202J1418D01*
G01Y21076D01*
G02X1397230Y24578I3502J0D01*
G01X1397232D01*
G02X1398649Y24278I-1J-3502D01*
G03X1398811I81J183D01*
G02X1400230Y24578I1418J-3202D01*
G02X1401649Y24278I1J-3502D01*
G03X1401811I81J183D01*
G02X1403230Y24578I1418J-3202D01*
G02X1404649Y24278I1J-3502D01*
G03X1404811I81J183D01*
G02X1406230Y24578I1418J-3202D01*
G37*
G36*
G01X334500Y24502D02*
G02X335919Y24202I1J-3502D01*
G03X336081I81J183D01*
G02X337500Y24502I1418J-3202D01*
G02X338919Y24202I1J-3502D01*
G03X339081I81J183D01*
G02X340498Y24502I1418J-3202D01*
G01X340500D01*
G02X344002Y21000I0J-3502D01*
G01Y20998D01*
G02X343702Y19581I-3502J1D01*
G03Y19419I183J-81D01*
G02X344002Y18000I-3202J-1418D01*
G02X343702Y16581I-3502J-1D01*
G03Y16419I183J-81D01*
G02X344002Y15002I-3202J-1418D01*
G01Y15000D01*
G02X340500Y11498I-3502J0D01*
G01X340498D01*
G02X339081Y11798I1J3502D01*
G03X338919I-81J-183D01*
G02X337500Y11498I-1418J3202D01*
G02X336081Y11798I-1J3502D01*
G03X335919I-81J-183D01*
G02X334500Y11498I-1418J3202D01*
G02X333081Y11798I-1J3502D01*
G03X332919I-81J-183D01*
G02X331500Y11498I-1418J3202D01*
G02X330081Y11798I-1J3502D01*
G03X329919I-81J-183D01*
G02X328500Y11498I-1418J3202D01*
G02X327081Y11798I-1J3502D01*
G03X326919I-81J-183D01*
G02X325502Y11498I-1418J3202D01*
G01X325500D01*
G02X321998Y15000I0J3502D01*
G01Y15002D01*
G02X322298Y16419I3502J-1D01*
G03Y16581I-183J81D01*
G02X321998Y18000I3202J1418D01*
G02X322298Y19419I3502J1D01*
G03Y19581I-183J81D01*
G02X321998Y20998I3202J1418D01*
G01Y21000D01*
G02X325500Y24502I3502J0D01*
G01X325502D01*
G02X326919Y24202I-1J-3502D01*
G03X327081I81J183D01*
G02X328500Y24502I1418J-3202D01*
G02X329919Y24202I1J-3502D01*
G03X330081I81J183D01*
G02X331500Y24502I1418J-3202D01*
G02X332919Y24202I1J-3502D01*
G03X333081I81J183D01*
G02X334500Y24502I1418J-3202D01*
G37*
G36*
G01X1438098Y14529D02*
X1438089Y14470D01*
X1438139Y14362D01*
X1438551Y14105D01*
X1438670Y14107D01*
X1438719Y14141D01*
G02X1441417Y14976I2699J-3944D01*
G02Y5418I0J-4779D01*
G02X1436638Y10194I0J4779D01*
G01Y10200D01*
G02X1436639Y10227I4774J-163D01*
G01Y10228D01*
G03X1436520Y10411I-200J0D01*
G01X1436185Y10560D01*
G03X1435969Y10525I-81J-183D01*
G02X1438098Y14529I-4551J4988D01*
G37*
G36*
G01X247547D02*
X247538Y14470D01*
X247588Y14362D01*
X248000Y14105D01*
X248119Y14107D01*
X248168Y14141D01*
G02X250866Y14976I2699J-3944D01*
G01X250868D01*
G02X246088Y10197I-1J-4779D01*
G01Y10228D01*
G03X245969Y10411I-200J0D01*
G01X245634Y10560D01*
G03X245418Y10525I-81J-183D01*
G02X247547Y14529I-4551J4988D01*
G37*
G36*
G01X1038045Y350989D02*
X1097848D01*
G02X1099262Y350403I0J-1999D01*
G01X1102411Y347254D01*
G02X1102997Y345840I-1413J-1414D01*
G01Y338600D01*
G03X1103056Y338458I200J0D01*
G01X1104207Y337307D01*
G02X1104214Y337300I-704J-711D01*
G03X1104357Y337240I143J140D01*
G01X1108329D01*
G03X1108471Y337299I0J200D01*
G01X1110941Y339769D01*
G03X1111000Y339911I-141J142D01*
G01Y342103D01*
G03X1110941Y342245I-200J0D01*
G01X1110093Y343093D01*
G02X1110090Y343096I705J708D01*
G03X1110048Y343129I-144J-139D01*
G02X1109800Y343560I251J431D01*
G01Y347960D01*
G02X1110300Y348460I500J0D01*
G01X1115700D01*
G02X1116200Y347960I0J-500D01*
G01Y343560D01*
G02X1115952Y343129I-499J0D01*
G03X1115910Y343096I102J-172D01*
G02X1115907Y343093I-708J705D01*
G01X1115059Y342245D01*
G03X1115000Y342103I141J-142D01*
G01Y339000D01*
G02X1114414Y337586I-1999J0D01*
G01X1110654Y333826D01*
G02X1109240Y333240I-1414J1413D01*
G01X1104674D01*
G03X1104532Y333181I0J-200D01*
G01X1103016Y331665D01*
G03X1102961Y331563I141J-142D01*
G01Y331562D01*
G02X1102411Y330526I-1964J379D01*
G01X1100743Y328858D01*
G02X1099329Y328272I-1414J1413D01*
G01X1047465D01*
G03X1047323Y328213I0J-200D01*
G01X1044172Y325062D01*
G03X1044113Y324920I141J-142D01*
G01Y282483D01*
G03X1044178Y282335I200J0D01*
G01X1044398Y282136D01*
G03X1044553Y282085I135J148D01*
G02X1044895Y282102I345J-3485D01*
G01X1044900D01*
G02X1048402Y278600I0J-3502D01*
G02X1046073Y275300I-3502J0D01*
G01X1046031Y275285D01*
X1045969Y275224D01*
X1045846Y274896D01*
G03X1045858Y274728I187J-71D01*
G02X1046302Y273023I-3058J-1707D01*
G01Y273020D01*
G02X1044231Y269823I-3503J0D01*
G03X1044113Y269641I82J-182D01*
G01Y209411D01*
G03X1044172Y209269I200J0D01*
G01X1049654Y203787D01*
G03X1049796Y203728I142J141D01*
G01X1080817D01*
G03X1080959Y203787I0J200D01*
G01X1109786Y232614D01*
G02X1111200Y233200I1414J-1413D01*
G01X1154289D01*
G03X1154431Y233259I0J200D01*
G01X1166141Y244969D01*
G03X1166200Y245111I-141J142D01*
G01Y258700D01*
G02X1166786Y260114I1999J0D01*
G01X1171646Y264974D01*
G03X1171695Y265177I-141J141D01*
G01X1171568Y265570D01*
X1171483Y265643D01*
X1171427Y265652D01*
G02X1168484Y269110I560J3458D01*
G02X1169696Y271760I3503J0D01*
G03X1169765Y271911I-131J151D01*
G01Y272215D01*
G03X1169696Y272366I-200J0D01*
G02X1168484Y275016I2291J2650D01*
G02X1175488I3502J0D01*
G02X1174276Y272366I-3503J0D01*
G03X1174207Y272215I131J-151D01*
G01Y271911D01*
G03X1174276Y271760I200J0D01*
G02X1175488Y269110I-2291J-2650D01*
G01Y269105D01*
G02X1175191Y267696I-3503J2D01*
G01X1175170Y267649D01*
X1175178Y267549D01*
X1175389Y267226D01*
G03X1175556Y267135I168J109D01*
G01X1184429D01*
G03X1184606Y267241I0J200D01*
G02X1190794I3094J-1642D01*
G03X1190971Y267135I177J94D01*
G01X1195493D01*
G03X1195688Y267290I0J200D01*
G02X1196013Y268153I3411J-792D01*
G03Y268343I-176J95D01*
G02X1195596Y270000I3087J1658D01*
G02X1196011Y271654I3504J0D01*
G03X1196010Y271842I-177J93D01*
G02X1195594Y273500I3091J1657D01*
G02X1196010Y275156I3506J0D01*
G03Y275344I-177J94D01*
G02X1195594Y277000I3090J1656D01*
G02X1202606I3506J0D01*
G02X1202190Y275344I-3506J0D01*
G03Y275156I177J-94D01*
G02X1202606Y273500I-3090J-1656D01*
G02X1202190Y271842I-3507J-1D01*
G03X1202189Y271654I176J-95D01*
G02X1202604Y270000I-3089J-1654D01*
G02X1202187Y268343I-3504J1D01*
G03Y268153I176J-95D01*
G02X1202512Y267290I-3086J-1655D01*
G03X1202707Y267135I195J45D01*
G01X1207229D01*
G03X1207406Y267241I0J200D01*
G02X1213594I3094J-1642D01*
G03X1213771Y267135I177J94D01*
G01X1218807D01*
G03X1218949Y267194I0J200D01*
G01X1221256Y269501D01*
G03X1221315Y269643I-141J142D01*
G01Y314349D01*
G02X1221901Y315763I1999J0D01*
G01X1224552Y318414D01*
G02X1225966Y319000I1414J-1413D01*
G01X1275500D01*
G02X1276914Y318414I0J-1999D01*
G01X1279414Y315914D01*
G02X1280000Y314500I-1413J-1414D01*
G01Y51500D01*
G02X1279414Y50086I-1999J0D01*
G01X1276914Y47586D01*
G02X1275500Y47000I-1414J1413D01*
G01X1115567D01*
G02X1114153Y47586I0J1999D01*
G01X1099586Y62153D01*
G02X1099000Y63567I1413J1414D01*
G01Y106106D01*
G03X1098941Y106248I-200J0D01*
G01X1095248Y109941D01*
G03X1095106Y110000I-142J-141D01*
G01X910000D01*
G02X908586Y110586I0J1999D01*
G01X901586Y117586D01*
G02X901000Y119000I1413J1414D01*
G01Y185000D01*
G02X901586Y186414I1999J0D01*
G01X905086Y189914D01*
G02X906500Y190500I1414J-1413D01*
G01X956551D01*
G02X957965Y189914I0J-1999D01*
G01X981058Y166821D01*
G03X981200Y166762I142J141D01*
G01X985094D01*
G03X985279Y166886I0J200D01*
G01X985303Y166942D01*
X985279Y167060D01*
X970074Y182265D01*
G02X969488Y183679I1413J1414D01*
G01Y200875D01*
G02X970074Y202289I1999J0D01*
G01X972219Y204434D01*
G02X973633Y205020I1414J-1413D01*
G01X1013854D01*
G02X1015268Y204434I0J-1999D01*
G01X1017914Y201788D01*
G02X1018500Y200374I-1413J-1414D01*
G01Y188811D01*
G03X1018624Y188626I200J0D01*
G01X1018680Y188602D01*
X1018798Y188626D01*
X1023586Y193414D01*
G03X1023645Y193556I-141J142D01*
G01Y213685D01*
G03X1023572Y213839I-200J0D01*
G02Y216161I953J1161D01*
G03X1023645Y216315I-127J154D01*
G01Y336589D01*
G02X1024231Y338003I1999J0D01*
G01X1036631Y350403D01*
G02X1038045Y350989I1414J-1413D01*
G37*
G36*
G01X486100Y319000D02*
X536375D01*
G02X537789Y318414I0J-1999D01*
G01X540259Y315944D01*
G02X540845Y314530I-1413J-1414D01*
G01Y269824D01*
G03X540904Y269682I200J0D01*
G01X543508Y267078D01*
G03X543650Y267019I142J141D01*
G01X548100D01*
G03X548280Y267132I0J200D01*
G02X554580I3150J-1533D01*
G03X554760Y267019I180J87D01*
G01X559271D01*
X559381Y267109D01*
X559395Y267180D01*
G02X559743Y268153I3435J-680D01*
G03Y268343I-176J95D01*
G02X559326Y270000I3087J1658D01*
G02X559741Y271654I3504J0D01*
G03X559740Y271842I-177J93D01*
G02X559324Y273500I3091J1657D01*
G02X559740Y275156I3506J0D01*
G03Y275344I-177J94D01*
G02X559324Y277000I3090J1656D01*
G02X566336I3506J0D01*
G02X565920Y275344I-3506J0D01*
G03Y275156I177J-94D01*
G02X566336Y273500I-3090J-1656D01*
G02X565920Y271842I-3507J-1D01*
G03X565919Y271654I176J-95D01*
G02X566334Y270000I-3089J-1654D01*
G02X565917Y268343I-3504J1D01*
G03Y268153I176J-95D01*
G02X566265Y267180I-3087J-1653D01*
G01X566279Y267109D01*
X566389Y267019D01*
X573137D01*
G03X573317Y267132I0J200D01*
G02X579617I3150J-1533D01*
G03X579797Y267019I180J87D01*
G01X592108D01*
G03X592250Y267078I0J200D01*
G01X594441Y269269D01*
G03X594500Y269411I-141J142D01*
G01Y292589D01*
G03X594441Y292731I-200J0D01*
G01X588586Y298586D01*
G02X588000Y300000I1413J1414D01*
G01Y308478D01*
G03X587956Y308604I-200J1D01*
G02X587182Y310800I2728J2196D01*
G01Y310801D01*
G02X587482Y312219I3502J0D01*
G03Y312381I-183J81D01*
G02X587182Y313798I3202J1418D01*
G01Y313800D01*
G02X590684Y317302I3502J0D01*
G01X590687D01*
G02X592071Y317016I-2J-3502D01*
G03X592150Y317000I78J184D01*
G01X595500D01*
G02X596914Y316414I0J-1999D01*
G01X599414Y313914D01*
G02X600000Y312500I-1413J-1414D01*
G01Y253238D01*
G03X600059Y253096I200J0D01*
G01X629696Y223459D01*
G03X629838Y223400I142J141D01*
G01X688200D01*
G02X689614Y222814I0J-1999D01*
G01X695517Y216911D01*
G02X696103Y215497I-1413J-1414D01*
G01Y210343D01*
G02X695517Y208929I-1999J0D01*
G01X686376Y199788D01*
G02X684962Y199202I-1414J1413D01*
G01X680373D01*
G03X680231Y199143I0J-200D01*
G01X679912Y198824D01*
G03X679853Y198682I141J-142D01*
G01Y172448D01*
G03X679912Y172306I200J0D01*
G01X685477Y166741D01*
G03X685619Y166682I142J141D01*
G01X730158D01*
G03X730348Y166819I0J200D01*
G01X730468Y167179D01*
G03X730399Y167402I-190J63D01*
G01X730398D01*
G02X730186Y167586I1201J1598D01*
G01X715686Y182086D01*
G02X715100Y183500I1413J1414D01*
G01Y200374D01*
G02X715686Y201788I1999J0D01*
G01X718332Y204434D01*
G02X719746Y205020I1414J-1413D01*
G01X759967D01*
G02X761381Y204434I0J-1999D01*
G01X763526Y202289D01*
G02X764112Y200875I-1413J-1414D01*
G01Y183679D01*
G02X763526Y182265I-1999J0D01*
G01X748847Y167586D01*
G02X748635Y167402I-1413J1414D01*
G01X748634D01*
G03X748565Y167179I121J-160D01*
G01X748685Y166819D01*
G03X748875Y166682I190J63D01*
G01X754000D01*
G03X754142Y166741I0J200D01*
G01X777315Y189914D01*
G02X778729Y190500I1414J-1413D01*
G01X827100D01*
G02X828514Y189914I0J-1999D01*
G01X832014Y186414D01*
G02X832600Y185000I-1413J-1414D01*
G01Y119000D01*
G02X832014Y117586I-1999J0D01*
G01X825014Y110586D01*
G02X823600Y110000I-1414J1413D01*
G01X638494D01*
G03X638352Y109941I0J-200D01*
G01X634659Y106248D01*
G03X634600Y106106I141J-142D01*
G01Y63567D01*
G02X634014Y62153I-1999J0D01*
G01X619447Y47586D01*
G02X618033Y47000I-1414J1413D01*
G01X486100D01*
G02X484686Y47586I0J1999D01*
G01X482186Y50086D01*
G02X481600Y51500I1413J1414D01*
G01Y314500D01*
G02X482186Y315914I1999J0D01*
G01X484686Y318414D01*
G02X486100Y319000I1414J-1413D01*
G37*
G36*
G01X704934Y286534D02*
G02X706684Y287002I1749J-3034D01*
G02Y279998I0J-3502D01*
G02X704934Y280466I-1J3502D01*
G03X704734I-100J-173D01*
G02X702984Y279998I-1749J3034D01*
G02Y287002I0J3502D01*
G02X704734Y286534I1J-3502D01*
G03X704934I100J173D01*
G37*
G54D57*
X1565500Y200472D03*
X1488500D03*
X1565500Y280472D03*
X1488500D03*
X1565500Y360472D03*
X1488500D03*
X1565500Y440472D03*
X1488500D03*
X1565500Y520472D03*
X1488500D03*
X243785Y200472D03*
X166785D03*
X243785Y280472D03*
X166785D03*
X243785Y360472D03*
X166785D03*
X243785Y440472D03*
X166785D03*
X243785Y520472D03*
X166785D03*
G54D56*
X725000Y292500D03*
X1320346Y289900D03*
Y245500D03*
X1332671Y190644D03*
X1334140Y146642D03*
X1320346Y112300D03*
Y67900D03*
X1173500Y298500D03*
X704240Y185000D03*
X632186Y338917D03*
X623500Y379000D03*
X441938Y309700D03*
Y265300D03*
Y220900D03*
Y176500D03*
Y132100D03*
Y87700D03*
X438100Y214500D03*
X430608Y211389D03*
X438100Y170000D03*
X428277Y167056D03*
G54D59*
X1451417Y10197D03*
X260866D03*
G54D60*
X940197Y200984D03*
X822087D03*
G54D58*
X1565500Y550000D03*
Y470000D03*
Y390000D03*
Y310000D03*
Y230000D03*
X1488500Y550000D03*
Y470000D03*
Y390000D03*
Y310000D03*
Y230000D03*
X243785Y550000D03*
Y470000D03*
Y390000D03*
Y310000D03*
Y230000D03*
X166785Y550000D03*
Y470000D03*
Y390000D03*
Y310000D03*
Y230000D03*
G54D55*
X263780Y659961D03*
X1444882D03*
G54D51*
X1851457Y220433D03*
X1856772Y360433D03*
G54D54*
X300866Y10197D03*
X1491417D03*
G54D52*
X1212478Y300181D03*
X1529100Y78500D03*
X231600Y81000D03*
X19685Y766166D03*
X1854331D03*
G54D50*
X940197Y313484D03*
X822087Y88484D03*
Y313484D03*
X940197Y88484D03*
G54D53*
X1673228Y236614D03*
Y411614D03*
X59055Y236614D03*
Y411594D03*
%LPC*%
G75*
G36*
G01X486511Y180500D02*
X555989D01*
G02X556131Y180441I0J-200D01*
G01X559541Y177031D01*
G02X559600Y176889I-141J-142D01*
G01Y164044D01*
G02X559495Y163867I-200J-1D01*
G03X557653Y160784I1659J-3083D01*
G03X557709Y160159I3502J-1D01*
G01X557718Y160110D01*
X557689Y160017D01*
X557131Y159459D01*
G02X556989Y159400I-142J141D01*
G01X547900D01*
G03X546486Y158814I0J-1999D01*
G01X542086Y154414D01*
G03X541500Y153000I1413J-1414D01*
G01Y133200D01*
G03X542086Y131786I1999J0D01*
G01X543266Y130606D01*
G03X544680Y130020I1414J1413D01*
G01X548775D01*
G02X548919Y129959I0J-200D01*
G03X553941I2511J2441D01*
G02X554085Y130020I144J-139D01*
G01X557169D01*
G02X557311Y129961I0J-200D01*
G01X559541Y127731D01*
G02X559600Y127589I-141J-142D01*
G01Y119287D01*
X559595Y119265D01*
G03X559505Y118477I3412J-789D01*
G03X559595Y117689I3502J1D01*
G01X559600Y117667D01*
Y114933D01*
X559595Y114911D01*
G03X559505Y114123I3412J-789D01*
G03X559595Y113335I3502J1D01*
G01X559600Y113313D01*
Y52911D01*
G02X559541Y52769I-200J0D01*
G01X557831Y51059D01*
G02X557689Y51000I-142J141D01*
G01X487011D01*
G02X486869Y51059I0J200D01*
G01X485659Y52269D01*
G02X485600Y52411I141J142D01*
G01Y179589D01*
G02X485659Y179731I200J0D01*
G01X486369Y180441D01*
G02X486511Y180500I142J-141D01*
G37*
G36*
G01X487011Y315000D02*
X535464D01*
G02X535606Y314941I0J-200D01*
G01X536786Y313761D01*
G02X536845Y313619I-141J-142D01*
G01Y268913D01*
G03X537431Y267499I1999J0D01*
G01X541325Y263605D01*
G03X542739Y263019I1414J1413D01*
G01X548986D01*
G02X549118Y262969I0J-200D01*
G03X551430Y262098I2311J2631D01*
G03X553742Y262969I1J3502D01*
G02X553874Y263019I132J-150D01*
G01X559400D01*
G02X559600Y262819I0J-200D01*
G01Y252487D01*
X559595Y252465D01*
G03X559505Y251677I3412J-789D01*
G03X559595Y250889I3502J1D01*
G01X559600Y250867D01*
Y248133D01*
X559595Y248111D01*
G03X559505Y247323I3412J-789D01*
G03X559595Y246535I3502J1D01*
G01X559600Y246513D01*
Y187911D01*
G02X559541Y187769I-200J0D01*
G01X556331Y184559D01*
G02X556189Y184500I-142J141D01*
G01X486511D01*
G02X486369Y184559I0J200D01*
G01X485659Y185269D01*
G02X485600Y185411I141J142D01*
G01Y313589D01*
G02X485659Y313731I200J0D01*
G01X486869Y314941D01*
G02X487011Y315000I142J-141D01*
G37*
G36*
G01X578911Y263019D02*
X584397D01*
G02X584539Y262960I0J-200D01*
G01X616061Y231438D01*
G02X616065Y231434I-139J-143D01*
G03X616100Y231398I1451J1376D01*
G01X627512Y219986D01*
G03X627548Y219951I1412J1416D01*
G02X627552Y219947I-139J-143D01*
G01X629913Y217586D01*
G03X631327Y217000I1414J1413D01*
G01X689689D01*
G02X689831Y216941I0J-200D01*
G01X692044Y214728D01*
G02X692103Y214586I-141J-142D01*
G01Y211254D01*
G02X692044Y211112I-200J0D01*
G01X684193Y203261D01*
G02X684051Y203202I-142J141D01*
G01X679462D01*
G03X678048Y202616I0J-1999D01*
G01X676439Y201007D01*
G03X675853Y199593I1413J-1414D01*
G01Y171537D01*
G03X676439Y170123I1999J0D01*
G01X683294Y163268D01*
G03X684708Y162682I1414J1413D01*
G01X754911D01*
G03X756325Y163268I0J1999D01*
G01X779498Y186441D01*
G02X779640Y186500I142J-141D01*
G01X826189D01*
G02X826331Y186441I0J-200D01*
G01X828541Y184231D01*
G02X828600Y184089I-141J-142D01*
G01Y119911D01*
G02X828541Y119769I-200J0D01*
G01X822831Y114059D01*
G02X822689Y114000I-142J141D01*
G01X637583D01*
G03X636169Y113414I0J-1999D01*
G01X631186Y108431D01*
G03X630600Y107017I1413J-1414D01*
G01Y64478D01*
G02X630541Y64336I-200J0D01*
G01X617264Y51059D01*
G02X617122Y51000I-142J141D01*
G01X565511D01*
G02X565369Y51059I0J200D01*
G01X563659Y52769D01*
G02X563600Y52911I141J142D01*
G01Y110578D01*
X563688Y110687D01*
X563757Y110702D01*
G03X566509Y114123I-750J3421D01*
G03X565839Y116182I-3501J-1D01*
G02Y116418I162J118D01*
G03X566509Y118477I-2831J2060D01*
G03X563757Y121898I-3502J0D01*
G01X563688Y121913D01*
X563600Y122022D01*
Y127789D01*
G02X563659Y127931I200J0D01*
G01X565689Y129961D01*
G02X565831Y130020I142J-141D01*
G01X571575D01*
G02X571719Y129959I0J-200D01*
G03X576741I2511J2441D01*
G02X576885Y130020I144J-139D01*
G01X580120D01*
G03X581534Y130606I0J1999D01*
G01X583514Y132586D01*
G03X584100Y134000I-1413J1414D01*
G01Y151100D01*
G03X583514Y152514I-1999J0D01*
G01X577214Y158814D01*
G03X575800Y159400I-1414J-1413D01*
G01X568081D01*
G02X567923Y159478I0J200D01*
G01X567700Y159766D01*
X567682Y159855D01*
X567694Y159901D01*
G03X567807Y160783I-3389J882D01*
G01Y160784D01*
G03X564305Y164286I-3502J0D01*
G03X564031Y164275I3J-3502D01*
G01X563989Y164272D01*
X563911Y164299D01*
X563664Y164528D01*
G02X563600Y164674I136J147D01*
G01Y243778D01*
X563688Y243887D01*
X563757Y243902D01*
G03X566509Y247323I-750J3421D01*
G03X565839Y249382I-3501J-1D01*
G02Y249618I162J118D01*
G03X566509Y251677I-2831J2060D01*
G03X563757Y255098I-3502J0D01*
G01X563688Y255113D01*
X563600Y255222D01*
Y262819D01*
G02X563800Y263019I200J0D01*
G01X574023D01*
X574155Y262969D01*
G03X578779I2312J2631D01*
G01X578911Y263019D01*
G37*
G36*
G01X719159Y199605D02*
X720515Y200961D01*
G02X720657Y201020I142J-141D01*
G01X759056D01*
G02X759198Y200961I0J-200D01*
G01X760053Y200106D01*
G02X760112Y199964I-141J-142D01*
G01Y184590D01*
G02X760053Y184448I-200J0D01*
G01X746664Y171059D01*
G02X746522Y171000I-142J141D01*
G01X732511D01*
G02X732369Y171059I0J200D01*
G01X719159Y184269D01*
G02X719100Y184411I141J142D01*
G01Y199463D01*
G02X719159Y199605I200J0D01*
G37*
G36*
G01X1190270Y263135D02*
X1195554D01*
G02X1195696Y263076I0J-200D01*
G01X1197941Y260831D01*
G02X1198000Y260689I-141J-142D01*
G01Y255072D01*
G02X1197880Y254888I-200J-1D01*
G03X1195775Y251677I1397J-3211D01*
G03X1196445Y249618I3502J1D01*
G02Y249382I-162J-118D01*
G03X1195775Y247323I2832J-2060D01*
G03X1197880Y244112I3502J0D01*
G02X1198000Y243928I-80J-183D01*
G01Y165611D01*
G02X1197941Y165469I-200J0D01*
G01X1195917Y163445D01*
X1195887Y163430D01*
G03X1194279Y161822I1538J-3146D01*
G02X1194241Y161769I-179J89D01*
G01X1194031Y161559D01*
G02X1193889Y161500I-142J141D01*
G01X1183800D01*
G03X1182386Y160914I0J-1999D01*
G01X1176414Y154942D01*
G03X1175828Y153528I1413J-1414D01*
G01Y132192D01*
G03X1176414Y130778I1999J0D01*
G01X1176795Y130397D01*
G03X1178209Y129811I1414J1413D01*
G01X1185266D01*
G02X1185397Y129762I0J-200D01*
G03X1190003I2303J2637D01*
G02X1190134Y129811I131J-151D01*
G01X1196878D01*
G02X1197020Y129752I0J-200D01*
G01X1197941Y128831D01*
G02X1198000Y128689I-141J-142D01*
G01Y121872D01*
G02X1197880Y121688I-200J-1D01*
G03X1195775Y118477I1397J-3211D01*
G03X1196445Y116418I3502J1D01*
G02Y116182I-162J-118D01*
G03X1195775Y114123I2832J-2060D01*
G03X1197880Y110912I3502J0D01*
G02X1198000Y110728I-80J-183D01*
G01Y52911D01*
G02X1197941Y52769I-200J0D01*
G01X1196231Y51059D01*
G02X1196089Y51000I-142J141D01*
G01X1116478D01*
G02X1116336Y51059I0J200D01*
G01X1103059Y64336D01*
G02X1103000Y64478I141J142D01*
G01Y107017D01*
G03X1102414Y108431I-1999J0D01*
G01X1097431Y113414D01*
G03X1096017Y114000I-1414J-1413D01*
G01X910911D01*
G02X910769Y114059I0J200D01*
G01X905059Y119769D01*
G02X905000Y119911I141J142D01*
G01Y184089D01*
G02X905059Y184231I200J0D01*
G01X907269Y186441D01*
G02X907411Y186500I142J-141D01*
G01X955640D01*
G02X955782Y186441I0J-200D01*
G01X978875Y163348D01*
G03X980289Y162762I1414J1413D01*
G01X1007447D01*
G03X1008861Y163348I0J1999D01*
G01X1018954Y173441D01*
G02X1019096Y173500I142J-141D01*
G01X1055500D01*
G03X1056914Y174086I0J1999D01*
G01X1111969Y229141D01*
G02X1112111Y229200I142J-141D01*
G01X1155200D01*
G03X1156614Y229786I0J1999D01*
G01X1169614Y242786D01*
G03X1170200Y244200I-1413J1414D01*
G01Y257789D01*
G02X1170259Y257931I200J0D01*
G01X1175404Y263076D01*
G02X1175546Y263135I142J-141D01*
G01X1185130D01*
G02X1185269Y263079I0J-200D01*
G03X1190131I2431J2522D01*
G02X1190270Y263135I139J-144D01*
G37*
G36*
G01X973547Y200106D02*
X974402Y200961D01*
G02X974544Y201020I142J-141D01*
G01X1012943D01*
G02X1013085Y200961I0J-200D01*
G01X1014441Y199605D01*
G02X1014500Y199463I-141J-142D01*
G01Y184411D01*
G02X1014441Y184269I-200J0D01*
G01X1001231Y171059D01*
G02X1001089Y171000I-142J141D01*
G01X987078D01*
G02X986936Y171059I0J200D01*
G01X973547Y184448D01*
G02X973488Y184590I141J142D01*
G01Y199964D01*
G02X973547Y200106I200J0D01*
G37*
G36*
G01X1204711Y180500D02*
X1275089D01*
G02X1275231Y180441I0J-200D01*
G01X1275941Y179731D01*
G02X1276000Y179589I-141J-142D01*
G01Y52411D01*
G02X1275941Y52269I-200J0D01*
G01X1274731Y51059D01*
G02X1274589Y51000I-142J141D01*
G01X1203911D01*
G02X1203769Y51059I0J200D01*
G01X1202059Y52769D01*
G02X1202000Y52911I141J142D01*
G01Y111851D01*
G02X1202042Y111974I200J0D01*
G03X1202779Y114123I-2765J2149D01*
G03X1202109Y116182I-3502J-1D01*
G02Y116418I162J118D01*
G03X1202779Y118477I-2832J2060D01*
G03X1202042Y120626I-3502J0D01*
G02X1202000Y120749I158J123D01*
G01Y128789D01*
G02X1202059Y128931I200J0D01*
G01X1202880Y129752D01*
G02X1203022Y129811I142J-141D01*
G01X1208066D01*
G02X1208197Y129762I0J-200D01*
G03X1212803I2303J2637D01*
G02X1212934Y129811I131J-151D01*
G01X1219382D01*
G03X1220796Y130397I0J1999D01*
G01X1224817Y134418D01*
G03X1225403Y135832I-1413J1414D01*
G01Y153697D01*
G03X1224817Y155111I-1999J0D01*
G01X1219014Y160914D01*
G03X1217600Y161500I-1414J-1413D01*
G01X1204111D01*
G02X1203969Y161559I0J200D01*
G01X1203736Y161792D01*
X1203721Y161822D01*
G03X1202113Y163430I-3146J-1538D01*
G01X1202083Y163445D01*
X1202059Y163469D01*
G02X1202000Y163611I141J142D01*
G01Y177789D01*
G02X1202059Y177931I200J0D01*
G01X1204569Y180441D01*
G02X1204711Y180500I142J-141D01*
G37*
G36*
G01X1226877Y315000D02*
X1274589D01*
G02X1274731Y314941I0J-200D01*
G01X1275941Y313731D01*
G02X1276000Y313589I-141J-142D01*
G01Y185411D01*
G02X1275941Y185269I-200J0D01*
G01X1275231Y184559D01*
G02X1275089Y184500I-142J141D01*
G01X1202200D01*
G02X1202000Y184700I0J200D01*
G01Y245051D01*
G02X1202042Y245174I200J0D01*
G03X1202779Y247323I-2765J2149D01*
G03X1202109Y249382I-3502J-1D01*
G02Y249618I162J118D01*
G03X1202779Y251677I-2832J2060D01*
G03X1202042Y253826I-3502J0D01*
G02X1202000Y253949I158J123D01*
G01Y260389D01*
G02X1202059Y260531I200J0D01*
G01X1204604Y263076D01*
G02X1204746Y263135I142J-141D01*
G01X1207930D01*
G02X1208069Y263079I0J-200D01*
G03X1212931I2431J2522D01*
G02X1213070Y263135I139J-144D01*
G01X1219718D01*
G03X1221132Y263721I0J1999D01*
G01X1224729Y267318D01*
G03X1225315Y268732I-1413J1414D01*
G01Y313438D01*
G02X1225374Y313580I200J0D01*
G01X1226735Y314941D01*
G02X1226877Y315000I142J-141D01*
G37*
%LPD*%
G75*
G36*
G01X595663Y243193D02*
G03X595740Y243199I23J199D01*
G02X596708Y243336I970J-3366D01*
G02Y236330I0J-3503D01*
G02X596329Y236351I4J3503D01*
G03X596251Y236345I-24J-199D01*
G02X595276Y236206I-977J3365D01*
G02X594263Y236356I1J3504D01*
G03X594178Y236363I-59J-191D01*
G02X593708Y236330I-480J3469D01*
G02X593460Y236338I-11J3503D01*
G03X593429I-16J-199D01*
G02X592476Y236206I-953J3372D01*
G02Y243214I0J3504D01*
G02X592747Y243203I-6J-3504D01*
G03X592774Y243209I-30J198D01*
G02X593707Y243336I935J-3376D01*
G01X593708D01*
G02X594713Y243188I-2J-3503D01*
G03X594798Y243181I59J191D01*
G02X595276Y243214I480J-3471D01*
G02X595663Y243193I4J-3503D01*
G37*
G36*
G01X41338Y17716D02*
G03X53150I5906J0D01*
G01Y23763D01*
G02X55572Y32155I15747J1D01*
G03X38916I-8328J5246D01*
G02X41338Y23763I-13327J-8392D01*
G01Y17716D01*
G37*
G36*
G01Y330708D02*
G03X53150I5906J0D01*
G01Y336755D01*
G02X55572Y345147I15747J1D01*
G03X38916I-8328J5246D01*
G02X41338Y336755I-13327J-8392D01*
G01Y330708D01*
G37*
G36*
G01X273622Y53148D02*
G03X285434I5906J0D01*
G01Y59195D01*
G02X287856Y67587I15747J1D01*
G03X271200I-8328J5246D01*
G02X273622Y59195I-13327J-8392D01*
G01Y53148D01*
G37*
G36*
G01X309055Y561023D02*
G03X320867I5906J0D01*
G01Y567070D01*
G02X323289Y575462I15747J1D01*
G03X306633I-8328J5246D01*
G02X309055Y567070I-13327J-8392D01*
G01Y561023D01*
G37*
G36*
G01X387796Y344488D02*
G03X399608I5906J0D01*
G01Y350535D01*
G02X402030Y358927I15747J1D01*
G03X385374I-8328J5246D01*
G02X387796Y350535I-13327J-8392D01*
G01Y344488D01*
G37*
G36*
G01X742126Y64961D02*
G03X753938I5906J0D01*
G01Y71008D01*
G02X756360Y79400I15747J1D01*
G03X739704I-8328J5246D01*
G02X742126Y71008I-13327J-8392D01*
G01Y64961D01*
G37*
G36*
G01Y344488D02*
G03X753938I5906J0D01*
G01Y350535D01*
G02X756360Y358927I15747J1D01*
G03X739704I-8328J5246D01*
G02X742126Y350535I-13327J-8392D01*
G01Y344488D01*
G37*
G36*
G01X978346Y64961D02*
G03X990158I5906J0D01*
G01Y71008D01*
G02X992580Y79400I15747J1D01*
G03X975924I-8328J5246D01*
G02X978346Y71008I-13327J-8392D01*
G01Y64961D01*
G37*
G36*
G01Y344488D02*
G03X990158I5906J0D01*
G01Y350535D01*
G02X992580Y358927I15747J1D01*
G03X975924I-8328J5246D01*
G02X978346Y350535I-13327J-8392D01*
G01Y344488D01*
G37*
G36*
G01X1332678D02*
G03X1344490I5906J0D01*
G01Y350535D01*
G02X1346912Y358927I15747J1D01*
G03X1330256I-8328J5246D01*
G02X1332678Y350535I-13327J-8392D01*
G01Y344488D01*
G37*
G36*
G01X1411418Y561023D02*
G03X1423230I5906J0D01*
G01Y567070D01*
G02X1425652Y575462I15747J1D01*
G03X1408996I-8328J5246D01*
G02X1411418Y567070I-13327J-8392D01*
G01Y561023D01*
G37*
G36*
G01X1446850Y53149D02*
G03X1458662I5906J0D01*
G01Y59196D01*
G02X1461084Y67588I15747J1D01*
G03X1444428I-8328J5246D01*
G02X1446850Y59196I-13327J-8392D01*
G01Y53149D01*
G37*
G36*
G01X1679134Y17716D02*
G03X1690946I5906J0D01*
G01Y23763D01*
G02X1693368Y32155I15747J1D01*
G03X1676712I-8328J5246D01*
G02X1679134Y23763I-13327J-8392D01*
G01Y17716D01*
G37*
G36*
G01Y330708D02*
G03X1690946I5906J0D01*
G01Y336755D01*
G02X1693368Y345147I15747J1D01*
G03X1676712I-8328J5246D01*
G02X1679134Y336755I-13327J-8392D01*
G01Y330708D01*
G37*
G36*
G01X1793306Y96457D02*
G03X1805118I5906J0D01*
G01Y102504D01*
G02X1807540Y110896I15747J1D01*
G03X1790884I-8328J5246D01*
G02X1793306Y102504I-13327J-8392D01*
G01Y96457D01*
G37*
G36*
G01Y478346D02*
G03X1805118I5906J0D01*
G01Y484393D01*
G02X1807540Y492785I15747J1D01*
G03X1790884I-8328J5246D01*
G02X1793306Y484393I-13327J-8392D01*
G01Y478346D01*
G37*
G54D17*
X134600Y150000D03*
Y134000D03*
X156785Y101285D03*
X187600Y106500D03*
X176785Y102000D03*
X211425Y106075D03*
X210925Y115575D03*
X317000Y58000D03*
Y74475D03*
Y64500D03*
X325500Y15000D03*
Y18000D03*
Y21000D03*
X340500D03*
Y18000D03*
Y15000D03*
X337500Y21000D03*
Y18000D03*
Y15000D03*
X334500Y21000D03*
Y18000D03*
Y15000D03*
X331500Y21000D03*
Y18000D03*
Y15000D03*
X328500Y21000D03*
Y18000D03*
Y15000D03*
X321500Y74475D03*
Y66500D03*
X325100Y64000D03*
X332500Y63300D03*
X330500Y74476D03*
X326000D03*
X396216Y46875D03*
X428277Y167056D03*
X438100Y170000D03*
X430608Y211389D03*
X438100Y214500D03*
X454738Y56000D03*
X451738D03*
X448738D03*
X445738D03*
X442738D03*
X454738Y68000D03*
Y65000D03*
Y62000D03*
Y59000D03*
X451738D03*
Y62000D03*
Y65000D03*
Y68000D03*
X448738Y59000D03*
Y62000D03*
Y65000D03*
Y68000D03*
X445738Y59000D03*
Y62000D03*
Y65000D03*
Y68000D03*
X442738Y59000D03*
Y62000D03*
Y65000D03*
Y68000D03*
X441938Y87700D03*
X454738Y112400D03*
Y109400D03*
Y106400D03*
Y103400D03*
X451738D03*
Y106400D03*
Y109400D03*
Y112400D03*
X448738Y103400D03*
Y106400D03*
Y109400D03*
Y112400D03*
X445738Y103400D03*
Y106400D03*
Y109400D03*
Y112400D03*
X442738Y103400D03*
Y106400D03*
Y109400D03*
Y112400D03*
X454738Y100400D03*
X451738D03*
X448738D03*
X445738D03*
X442738D03*
X454738Y147800D03*
X451738D03*
X448738D03*
X445738D03*
X442738D03*
X454738Y144800D03*
X451738D03*
X448738D03*
X445738D03*
X442738D03*
X441938Y132100D03*
X454738Y156800D03*
Y153800D03*
Y150800D03*
X451738D03*
Y153800D03*
Y156800D03*
X448738Y150800D03*
Y153800D03*
Y156800D03*
X445738Y150800D03*
Y153800D03*
Y156800D03*
X442738Y150800D03*
Y153800D03*
Y156800D03*
X441938Y176500D03*
X454738Y201200D03*
Y198200D03*
Y195200D03*
Y192200D03*
X451738D03*
Y195200D03*
Y198200D03*
Y201200D03*
X448738Y192200D03*
Y195200D03*
Y198200D03*
Y201200D03*
X445738Y192200D03*
Y195200D03*
Y198200D03*
Y201200D03*
X442738Y192200D03*
Y195200D03*
Y198200D03*
Y201200D03*
X454738Y189200D03*
X451738D03*
X448738D03*
X445738D03*
X442738D03*
X454738Y239600D03*
Y236600D03*
X451738D03*
Y239600D03*
X448738Y236600D03*
Y239600D03*
X445738Y236600D03*
Y239600D03*
X442738Y236600D03*
Y239600D03*
X454738Y233600D03*
X451738D03*
X448738D03*
X445738D03*
X442738D03*
X441938Y220900D03*
X454738Y245600D03*
Y242600D03*
X451738D03*
Y245600D03*
X448738Y242600D03*
Y245600D03*
X445738Y242600D03*
Y245600D03*
X442738Y242600D03*
Y245600D03*
X441938Y265300D03*
X448738Y278000D03*
X451738D03*
X454738D03*
X448738Y290000D03*
Y287000D03*
Y284000D03*
Y281000D03*
X451738Y290000D03*
Y287000D03*
Y284000D03*
Y281000D03*
X454738D03*
Y284000D03*
Y287000D03*
Y290000D03*
X445738D03*
Y287000D03*
Y284000D03*
Y281000D03*
Y278000D03*
X442738Y290000D03*
Y287000D03*
Y284000D03*
Y281000D03*
Y278000D03*
X441938Y309700D03*
X517409Y322000D03*
X506309Y329000D03*
Y322000D03*
X517410Y329000D03*
X551430Y132400D03*
X561155Y160784D03*
X551430Y265600D03*
X563007Y118477D03*
Y114123D03*
X562830Y133300D03*
Y136800D03*
Y140300D03*
Y143800D03*
X574230Y132400D03*
X564305Y160784D03*
X563007Y251677D03*
X576467Y265600D03*
X563007Y247323D03*
X562830Y270000D03*
Y266500D03*
X590298Y282890D03*
X562830Y277000D03*
X571325Y292757D03*
X590298Y276984D03*
X562830Y273500D03*
X571542Y289065D03*
X565091Y302592D03*
X570443Y302702D03*
X595276Y239710D03*
X592476D03*
X620600Y239161D03*
X605800Y256500D03*
X609637Y254523D03*
X605700Y259500D03*
X616184Y267000D03*
X604684D03*
X612684Y297000D03*
X616684Y294500D03*
X602928Y293969D03*
X606084Y293100D03*
X600875Y295937D03*
X616184Y276000D03*
X604684D03*
Y285000D03*
X616184D03*
X590684Y313800D03*
Y310800D03*
X616684Y307975D03*
X622184Y308000D03*
X608259Y305000D03*
X618500Y333500D03*
X639010Y236377D03*
X640684Y264500D03*
Y269000D03*
X645900Y242200D03*
X644502Y246839D03*
X649200Y254500D03*
X650100Y251500D03*
X623684Y281000D03*
X637684Y280575D03*
X629018Y277500D03*
X625684Y273499D03*
X630308Y284500D03*
X632186Y338917D03*
X623500Y379000D03*
X676638Y230894D03*
X658600Y237700D03*
X655600D03*
X681684Y230820D03*
X657259Y263000D03*
X674800Y269600D03*
X660684Y262500D03*
X654100Y263000D03*
X651100Y266000D03*
X679184Y278980D03*
X673684Y280950D03*
X676684D03*
X670184Y288500D03*
X662184Y280500D03*
Y288500D03*
Y284500D03*
X679184Y273190D03*
X676184Y274000D03*
X657500Y330075D03*
X662075Y320000D03*
X675100Y304500D03*
X662125Y308500D03*
X662100Y304500D03*
X658925Y320000D03*
X702223Y197419D03*
X704240Y185000D03*
X689684Y230762D03*
X683592Y259908D03*
X688945Y259761D03*
X695259Y248020D03*
X706984Y261100D03*
X710084D03*
X691794Y261073D03*
X692109Y248020D03*
X686784Y268100D03*
X695584D03*
X698433Y247119D03*
X685884Y297000D03*
X702984Y283500D03*
X706684D03*
X702984Y272400D03*
X706684D03*
X686784Y278000D03*
X695584D03*
X686784Y287900D03*
X695684D03*
X710900Y324100D03*
X696613Y324032D03*
X693904D03*
X691759Y309000D03*
X712000Y215500D03*
X730600Y270000D03*
X727600D03*
X717384Y273400D03*
X719484Y278980D03*
X725000Y292500D03*
X722925Y299500D03*
X719433Y328087D03*
X734500Y307425D03*
X717401Y329996D03*
X770700Y206900D03*
X776000Y206600D03*
X862600Y29500D03*
X867100Y28000D03*
X872533Y29432D03*
X867100Y31500D03*
X887500Y355680D03*
X885100Y361500D03*
X885265Y381000D03*
X878175Y374100D03*
Y364709D03*
X894500Y396500D03*
X954200Y200200D03*
X954600Y207200D03*
X978600Y310955D03*
X1030100Y207500D03*
X1034537Y201437D03*
X1024600Y185000D03*
X1027675Y215000D03*
X1024525D03*
X1034360Y254000D03*
X1032500Y281800D03*
X1029500D03*
X1044900Y278600D03*
X1042800Y273020D03*
X1017300Y322500D03*
X1026270Y303729D03*
X1023492Y346593D03*
X1021414Y355979D03*
X1017300Y385600D03*
X1047163Y197437D03*
X1061600Y228000D03*
X1064600D03*
X1073600D03*
X1070600D03*
X1066600Y264100D03*
X1074430Y256461D03*
X1059300Y268500D03*
X1055600D03*
X1070525Y243000D03*
X1066700Y274000D03*
Y283900D03*
X1052200Y290900D03*
X1055300D03*
X1070490Y290927D03*
X1055600Y279600D03*
X1059300D03*
X1073339Y292239D03*
X1062600Y305000D03*
X1070175Y303980D03*
X1067025D03*
X1072600Y324000D03*
X1064600D03*
X1065800Y339500D03*
X1063300D03*
X1073800D03*
X1071300D03*
X1092100Y263500D03*
X1100100Y243500D03*
X1100500Y263500D03*
X1100100Y247500D03*
X1075500Y264100D03*
X1085600Y271050D03*
X1101500Y271500D03*
X1083100Y273020D03*
X1088079Y274980D03*
X1087100Y282500D03*
X1101600Y289500D03*
X1080600Y294000D03*
X1075500Y274000D03*
Y283900D03*
X1102600Y296000D03*
X1083100Y278810D03*
X1086100Y278000D03*
X1103661Y307700D03*
X1080600Y324000D03*
X1081800Y339500D03*
X1079300D03*
X1086800D03*
X1089300D03*
X1094500Y355600D03*
Y360500D03*
X1129800Y265400D03*
X1131976Y267500D03*
X1108100Y289000D03*
X1121600Y287500D03*
Y283000D03*
X1105025Y289000D03*
X1111100Y291500D03*
Y285000D03*
X1121100Y296000D03*
X1124600Y271425D03*
X1132113Y274500D03*
X1112000Y296000D03*
X1106661Y307700D03*
X1111100Y300500D03*
X1118000Y303500D03*
X1123100Y322500D03*
Y319500D03*
X1130100Y305174D03*
X1130510Y307720D03*
X1123400Y356300D03*
X1132000Y367000D03*
X1145600Y257500D03*
X1149600Y255000D03*
X1160990Y252134D03*
X1146100Y267000D03*
X1157600D03*
X1156200Y258900D03*
X1145600Y244025D03*
X1140100Y244000D03*
X1154025Y247000D03*
X1163266Y255311D03*
X1156584Y292488D03*
X1156509Y295396D03*
X1157600Y276000D03*
X1146100D03*
Y285000D03*
X1157600D03*
X1136000Y278953D03*
X1157800Y312050D03*
X1157138Y303000D03*
X1141600Y312839D03*
X1141500Y347500D03*
X1138500D03*
X1162425Y340500D03*
X1166000Y352500D03*
X1163000D03*
X1153500Y342500D03*
X1187700Y132400D03*
X1197425Y160284D03*
X1187700Y265600D03*
X1171986Y269110D03*
X1173500Y298500D03*
X1196500Y293284D03*
X1171986Y275016D03*
X1176200Y316500D03*
X1173200D03*
X1176000Y350000D03*
X1167800Y355000D03*
X1168200Y349700D03*
X1178900Y359620D03*
X1179500Y350000D03*
Y355000D03*
X1199277Y118477D03*
Y114123D03*
X1210500Y132400D03*
X1199100Y140300D03*
Y133300D03*
Y143800D03*
Y136800D03*
X1200575Y160284D03*
X1199277Y247323D03*
X1210500Y265600D03*
X1199277Y251677D03*
X1199100Y270000D03*
Y266500D03*
X1201500Y293284D03*
X1199100Y277000D03*
Y273500D03*
X1201037Y318912D03*
X1197127Y314264D03*
X1244874Y330000D03*
X1255975D03*
Y337000D03*
X1307700Y78900D03*
Y81900D03*
X1310700D03*
Y78900D03*
X1313700Y81900D03*
Y78900D03*
X1307700Y84900D03*
Y87900D03*
X1310700D03*
Y84900D03*
X1313700Y87900D03*
Y84900D03*
X1307700Y90900D03*
X1310700D03*
X1313700D03*
X1307700Y123300D03*
Y126300D03*
X1310700D03*
Y123300D03*
X1313700Y126300D03*
Y123300D03*
X1307700Y129300D03*
Y132300D03*
Y135300D03*
X1310700D03*
Y132300D03*
Y129300D03*
X1313700Y135300D03*
Y132300D03*
Y129300D03*
Y167700D03*
Y170700D03*
Y173700D03*
Y176700D03*
X1310700Y167700D03*
Y170700D03*
Y173700D03*
Y176700D03*
X1307700D03*
Y173700D03*
Y170700D03*
Y167700D03*
X1313700Y179700D03*
X1310700D03*
X1307700D03*
Y212100D03*
Y215100D03*
X1310700D03*
Y212100D03*
X1313700Y215100D03*
Y212100D03*
X1307700Y218100D03*
Y221100D03*
Y224100D03*
X1310700D03*
Y221100D03*
Y218100D03*
X1313700Y224100D03*
Y221100D03*
Y218100D03*
X1307700Y256500D03*
Y259500D03*
X1310700D03*
Y256500D03*
X1313700Y259500D03*
Y256500D03*
X1307700Y262500D03*
Y265500D03*
Y268500D03*
X1310700D03*
Y265500D03*
Y262500D03*
X1313700Y268500D03*
Y265500D03*
Y262500D03*
X1307700Y300900D03*
Y303900D03*
X1310700D03*
Y300900D03*
X1313700Y303900D03*
Y300900D03*
X1307700Y306900D03*
Y309900D03*
Y312900D03*
X1310700D03*
Y309900D03*
Y306900D03*
X1313700Y309900D03*
Y306900D03*
X1316700Y81900D03*
Y78900D03*
X1319700Y81900D03*
Y78900D03*
X1316700Y87900D03*
Y84900D03*
X1319700Y87900D03*
Y84900D03*
X1320346Y67900D03*
X1316700Y90900D03*
X1319700D03*
X1320346Y112300D03*
X1316700Y126300D03*
Y123300D03*
X1319700Y126300D03*
Y123300D03*
X1316700Y135300D03*
Y132300D03*
Y129300D03*
X1319700Y135300D03*
Y132300D03*
Y129300D03*
X1334140Y146642D03*
X1319700Y167700D03*
Y170700D03*
Y173700D03*
Y176700D03*
X1316700Y167700D03*
Y170700D03*
Y173700D03*
Y176700D03*
X1324100Y150500D03*
X1320346Y156700D03*
X1324100Y194900D03*
X1332671Y190644D03*
X1320346Y201100D03*
X1316700Y215100D03*
Y212100D03*
X1319700Y215100D03*
Y212100D03*
X1316700Y224100D03*
Y221100D03*
Y218100D03*
X1319700Y224100D03*
Y221100D03*
Y218100D03*
X1316700Y259500D03*
Y256500D03*
X1319700Y259500D03*
Y256500D03*
X1316700Y268500D03*
Y265500D03*
Y262500D03*
X1319700Y268500D03*
Y265500D03*
Y262500D03*
X1320346Y245500D03*
Y289900D03*
X1316700Y303900D03*
Y300900D03*
X1319700Y303900D03*
Y300900D03*
X1316700Y306900D03*
X1406230Y21076D03*
Y18076D03*
Y15076D03*
X1403230Y21076D03*
Y18076D03*
Y15076D03*
X1400230Y21076D03*
Y18076D03*
Y15076D03*
X1397230D03*
Y18076D03*
Y21076D03*
X1412230D03*
Y18076D03*
Y15076D03*
X1409230Y21076D03*
Y18076D03*
Y15076D03*
X1498180Y63500D03*
X1494728Y83500D03*
X1490000Y80500D03*
X1499228Y74500D03*
X1494728Y66500D03*
X1490228D03*
X1505100Y64500D03*
X1503728Y74477D03*
X1527100Y98925D03*
X1524600Y111500D03*
X1551000Y96500D03*
X1567500Y67000D03*
X1597100Y145000D03*
Y126000D03*
X1614100Y125000D03*
X1618100Y148925D03*
X1647800Y83200D03*
Y77200D03*
Y80200D03*
X1622295Y114940D03*
X1625370Y103940D03*
X1642037Y104134D03*
X1643537Y101434D03*
X1640037D03*
X1638537Y104134D03*
X1645537D03*
X1647037Y101434D03*
X1632336Y109117D03*
X1631323Y115140D03*
X1624500Y142500D03*
Y146000D03*
X1622295Y118940D03*
X1644917Y124581D03*
X1641932Y122969D03*
X1650117Y180000D03*
X1636600Y173500D03*
X1622100Y155931D03*
X1626000Y163500D03*
Y167500D03*
X1626925Y156000D03*
X1629000Y175000D03*
X1624000Y189000D03*
X1642000Y184500D03*
X1645000D03*
X1660250Y113860D03*
X1657050Y116760D03*
Y113860D03*
X1660250Y116760D03*
X1669800Y120400D03*
X1675800D03*
X1651037Y99734D03*
X1658500Y138000D03*
X1672800Y120400D03*
X1656657Y127365D03*
X1651325Y125076D03*
X1676350Y160251D03*
X1672050Y181550D03*
X1657500Y191500D03*
X1664000Y202500D03*
X1661500Y199000D03*
X1667600Y198500D03*
X1658000Y179500D03*
X1654000Y192500D03*
X1660000Y193500D03*
X1692000Y76570D03*
X1695500Y76500D03*
X1706100Y92000D03*
X1701350Y114250D03*
X1696600Y119000D03*
X1682500Y121825D03*
X1697976Y148000D03*
X1690100Y127375D03*
X1688100Y145560D03*
X1705100Y140500D03*
X1707100Y142500D03*
X1685000Y133000D03*
X1702600Y171500D03*
X1697976Y164500D03*
Y159000D03*
Y175500D03*
Y170000D03*
Y153500D03*
X1680000Y156500D03*
X1688100Y173060D03*
Y162060D03*
X1709600Y158000D03*
X1701000Y159000D03*
Y164500D03*
X1685975Y186500D03*
X1701100Y182000D03*
X1688100Y184220D03*
X1697975Y181000D03*
X1704600Y201500D03*
X1718675Y88000D03*
X1719075Y107016D03*
Y112000D03*
X1718675Y99000D03*
Y93500D03*
X1713524Y109500D03*
Y114500D03*
X1721685Y95940D03*
X1738000Y124500D03*
X1721000Y142525D03*
X1714100Y144925D03*
X1713525Y134500D03*
Y129500D03*
X1713524Y119500D03*
X1727100Y164280D03*
X1715525Y168500D03*
Y153000D03*
X1722063Y156962D03*
X1726099Y153000D03*
X1720524Y175000D03*
X1717600Y158000D03*
X1728475Y175000D03*
X1731925Y199000D03*
X1714175Y187000D03*
X1721500Y205000D03*
X1721600Y194760D03*
Y198500D03*
X1767525Y114016D03*
X1759600Y114500D03*
X1767425Y107000D03*
X1761600Y124524D03*
X1764000Y142525D03*
X1767425Y137000D03*
X1768500Y142525D03*
X1764100Y119500D03*
X1764000Y158025D03*
X1759925Y178900D03*
X1768500Y158025D03*
X1763925Y170984D03*
Y155484D03*
X1766925Y181500D03*
X1769425Y203000D03*
X1754925D03*
X1750563Y198000D03*
X1747925Y204000D03*
X1751600Y258000D03*
Y255500D03*
X1740600Y258000D03*
Y255500D03*
Y248000D03*
Y250500D03*
Y253000D03*
X1751600D03*
Y250500D03*
Y248000D03*
X1766432Y250301D03*
Y247301D03*
X1769300Y329400D03*
Y340600D03*
X1769692Y334649D03*
X1767700Y346200D03*
X1767600Y350000D03*
X1772975Y109500D03*
Y104500D03*
X1773076Y117500D03*
X1773000Y142525D03*
X1773500Y129500D03*
X1772975Y124500D03*
X1773000Y158000D03*
X1772600Y177300D03*
X1800100Y187500D03*
X1778000Y189500D03*
X1789600Y247000D03*
X1783932Y250357D03*
Y247357D03*
X1775432Y250357D03*
Y247357D03*
X1795600Y308000D03*
X1777375Y356300D03*
X1777383Y352305D03*
X1784035Y389535D03*
X1781535D03*
X1784035Y386935D03*
X1781535D03*
X1778838Y389508D03*
Y386908D03*
X1781535Y402935D03*
X1784035D03*
X1778838Y402908D03*
X1781535Y405535D03*
X1784035D03*
X1778838Y405508D03*
X1817500Y188000D03*
X1809600Y195000D03*
X1811500Y186000D03*
X1842164Y419238D03*
X1847164D03*
X1837164D03*
X1852164D03*
X1842164Y432338D03*
X1847164Y430568D03*
X1852164Y435538D03*
X1837164Y428238D03*
G54D20*
X166785Y230000D03*
Y310000D03*
Y390000D03*
Y470000D03*
Y550000D03*
X243785Y230000D03*
Y310000D03*
Y390000D03*
Y470000D03*
Y550000D03*
X1488500Y230000D03*
Y310000D03*
Y390000D03*
Y470000D03*
Y550000D03*
X1565500Y230000D03*
Y310000D03*
Y390000D03*
Y470000D03*
Y550000D03*
G54D47*
X1846142Y270433D03*
X1856772D03*
X1846142Y280433D03*
Y290433D03*
Y300433D03*
X1856772D03*
Y290433D03*
Y280433D03*
X1848957Y324213D03*
X1843957Y329213D03*
X1848957Y314213D03*
X1843957Y319213D03*
X1853957Y329213D03*
Y319213D03*
X1848957Y334213D03*
Y344213D03*
X1843957Y339213D03*
Y349213D03*
X1853957D03*
Y339213D03*
X1858957Y344213D03*
Y334213D03*
G54D15*
X45275Y236614D03*
Y411594D03*
X72835Y236614D03*
X68898Y226771D03*
X59055Y222834D03*
X49212Y226771D03*
X68898Y246457D03*
X49212D03*
X59055Y250394D03*
X68898Y421437D03*
X72835Y411594D03*
X68898Y401751D03*
X59055Y397814D03*
X49212Y401751D03*
Y421437D03*
X59055Y425374D03*
X1673228Y222834D03*
X1663385Y226771D03*
X1659448Y236614D03*
X1663385Y246457D03*
X1673228Y250394D03*
Y397834D03*
X1663385Y401771D03*
X1659448Y411614D03*
X1663385Y421457D03*
X1673228Y425394D03*
X1687008Y236614D03*
X1683071Y226771D03*
Y246457D03*
Y421457D03*
X1687008Y411614D03*
X1683071Y401771D03*
G54D42*
X1642915Y111950D03*
X1639372Y114450D03*
X1646458Y111950D03*
X1642915Y114450D03*
X1639372Y111950D03*
X1646458Y114450D03*
X1650002Y111950D03*
Y114450D03*
G54D28*
X468946Y338216D03*
X465946D03*
X468946Y341216D03*
X465946D03*
X458946Y338216D03*
X455946D03*
X458946Y341216D03*
X455946D03*
Y357216D03*
X458946D03*
X468946Y357016D03*
X465946D03*
X471946Y338216D03*
Y341216D03*
X481446Y338216D03*
X478446D03*
X481446Y341216D03*
X478446D03*
X484446Y338216D03*
Y341216D03*
X471946Y357016D03*
X528084Y77900D03*
Y74900D03*
Y71900D03*
X525084Y77900D03*
Y74900D03*
Y71900D03*
X522084Y77900D03*
Y74900D03*
Y71900D03*
X525084Y116300D03*
X522084D03*
X528084D03*
X525084Y122300D03*
X522084D03*
X525084Y119300D03*
X522084D03*
X528084Y122300D03*
Y119300D03*
X525084Y166700D03*
X522084D03*
X525084Y160700D03*
Y163700D03*
X522084D03*
Y160700D03*
Y205100D03*
Y208100D03*
X525084D03*
Y205100D03*
X522084Y211100D03*
X525084D03*
X522084Y249500D03*
Y252500D03*
X525084D03*
Y249500D03*
X522084Y255500D03*
X525084D03*
X528084Y252500D03*
Y249500D03*
Y255500D03*
Y299900D03*
X525084D03*
X522084D03*
X528084Y296900D03*
X525084D03*
X522084D03*
X528084Y293900D03*
X525084D03*
X522084D03*
X531084Y77900D03*
Y74900D03*
Y71900D03*
Y299900D03*
Y296900D03*
Y293900D03*
X586184Y117800D03*
X583184D03*
X580184D03*
X586184Y114800D03*
X583184D03*
X580184D03*
X586184Y111800D03*
X583184D03*
X580184D03*
X586184Y108800D03*
X583184D03*
X580184D03*
X586184Y105800D03*
X583184D03*
X580184D03*
Y126800D03*
X583184D03*
X586184D03*
Y123800D03*
X583184D03*
X580184D03*
X586184Y120800D03*
X583184D03*
X580184D03*
X583184Y239000D03*
X580184D03*
X583184Y242000D03*
X580184D03*
X583184Y254000D03*
Y251000D03*
Y248000D03*
Y245000D03*
X580184D03*
Y248000D03*
Y251000D03*
Y254000D03*
X583184Y260000D03*
Y257000D03*
X580184D03*
Y260000D03*
X620466Y246839D03*
X664484Y212500D03*
X666984D03*
X672484D03*
X674984D03*
X679484D03*
X681984D03*
X685484D03*
X687984D03*
X1240200Y77900D03*
Y74900D03*
Y71900D03*
Y68900D03*
Y65900D03*
X1237200D03*
Y68900D03*
Y71900D03*
Y74900D03*
Y77900D03*
X1234200Y65900D03*
Y68900D03*
Y71900D03*
Y74900D03*
Y77900D03*
X1231200Y65900D03*
Y68900D03*
Y71900D03*
Y74900D03*
Y77900D03*
X1234200Y116300D03*
Y113300D03*
Y110300D03*
X1237200Y116300D03*
Y113300D03*
Y110300D03*
X1240200D03*
Y113300D03*
Y116300D03*
X1234200Y122300D03*
Y119300D03*
X1237200Y122300D03*
Y119300D03*
X1240200D03*
Y122300D03*
X1237200Y166700D03*
Y163700D03*
Y160700D03*
Y157700D03*
Y154700D03*
X1240200D03*
Y157700D03*
Y160700D03*
Y163700D03*
Y166700D03*
X1237200Y208100D03*
X1240200D03*
X1237200Y211100D03*
X1240200D03*
X1234200Y252500D03*
X1237200D03*
X1234200Y255500D03*
X1237200D03*
X1240200Y252500D03*
Y255500D03*
Y299900D03*
Y296900D03*
X1237200D03*
Y299900D03*
X1234200Y296900D03*
Y299900D03*
X1231200Y296900D03*
Y299900D03*
X1657050Y102380D03*
X1685100Y127500D03*
X1692600Y135975D03*
X1751600Y238000D03*
Y235500D03*
X1740600D03*
Y238000D03*
X1751600Y233000D03*
X1740600D03*
X1766447Y239798D03*
Y242798D03*
X1751600Y240500D03*
X1740600D03*
X1783947Y239798D03*
Y242798D03*
X1775447Y239798D03*
Y242798D03*
X1789600Y243500D03*
G54D29*
X649059Y314000D03*
X1491918Y107773D03*
Y110773D03*
Y113773D03*
Y104773D03*
X1488918D03*
Y113773D03*
Y110773D03*
Y107773D03*
X1485918Y104773D03*
Y113773D03*
Y110773D03*
Y107773D03*
X1482918Y104773D03*
Y113773D03*
Y110773D03*
Y107773D03*
X1618800Y76700D03*
X1615800Y82700D03*
Y79700D03*
Y76700D03*
X1618800Y79700D03*
Y82700D03*
X1727200Y104500D03*
X1728600Y387500D03*
X1731100D03*
X1733600D03*
X1770575Y137000D03*
X1762454Y320347D03*
X1742109Y345235D03*
Y342435D03*
X1747416Y348293D03*
X1747909Y345335D03*
Y342535D03*
X1744909Y345335D03*
Y342535D03*
X1742109Y339635D03*
Y336835D03*
Y334035D03*
X1747909Y339735D03*
Y336935D03*
Y334135D03*
X1744909Y339735D03*
Y336935D03*
Y334135D03*
X1767151Y333311D03*
X1777532Y328322D03*
X1777459Y332322D03*
X1777383Y348288D03*
G54D34*
X802087Y200984D03*
X792087D03*
X822087D03*
X812087D03*
X920197D03*
X910197D03*
X940197D03*
X930197D03*
G54D37*
X825900Y362200D03*
Y372200D03*
X866400Y362200D03*
Y382200D03*
X906900Y362200D03*
Y372200D03*
G54D21*
X163878Y601693D03*
X156004D03*
X163878Y609567D03*
Y617441D03*
Y625315D03*
Y633189D03*
X156004Y609567D03*
Y617441D03*
Y625315D03*
Y633189D03*
X163878Y641063D03*
Y648937D03*
Y656811D03*
X156004Y641063D03*
Y648937D03*
Y656811D03*
X163878Y664685D03*
X156004D03*
X1587107Y601693D03*
Y609567D03*
Y617441D03*
Y625315D03*
Y633189D03*
Y641063D03*
Y648937D03*
Y656811D03*
Y664685D03*
X1594981Y601693D03*
Y609567D03*
Y617441D03*
Y625315D03*
Y633189D03*
Y641063D03*
Y648937D03*
Y656811D03*
Y664685D03*
G54D31*
X681498Y575042D03*
Y565042D03*
X681604Y593187D03*
Y603187D03*
X997833Y575042D03*
Y565042D03*
Y593187D03*
Y603187D03*
G54D43*
X1848583Y99212D03*
X1848582Y481693D03*
G54D18*
X137303Y601693D03*
Y609567D03*
Y617441D03*
Y625315D03*
Y633189D03*
Y641063D03*
Y648937D03*
Y656811D03*
Y664685D03*
X145177Y601693D03*
Y609567D03*
Y617441D03*
Y625315D03*
Y633189D03*
Y641063D03*
Y648937D03*
Y656811D03*
Y664685D03*
X192126Y633189D03*
Y625315D03*
Y617441D03*
X200000Y633189D03*
Y625315D03*
Y617441D03*
X215748Y633189D03*
Y625315D03*
Y617441D03*
X223622Y633189D03*
Y625315D03*
Y617441D03*
X250866Y10197D03*
X255906Y617441D03*
X248032D03*
X255906Y625315D03*
Y633189D03*
X248032D03*
Y625315D03*
X279646Y23012D03*
Y13012D03*
X274646Y18012D03*
X284646Y8012D03*
X274646D03*
X260866Y10197D03*
X279528Y617441D03*
X271654D03*
X279528Y625315D03*
Y633189D03*
X271654D03*
Y625315D03*
X289646Y23012D03*
Y13012D03*
X295276Y617441D03*
Y625315D03*
Y633189D03*
X303150D03*
Y625315D03*
Y617441D03*
X1437008D03*
X1429134D03*
X1437008Y625315D03*
Y633189D03*
X1429134D03*
Y625315D03*
X1465197Y18012D03*
Y8012D03*
X1451417Y10197D03*
X1441417D03*
X1460630Y617441D03*
X1452756D03*
X1460630Y625315D03*
Y633189D03*
X1452756D03*
Y625315D03*
X1480197Y23012D03*
X1470197D03*
X1480197Y13012D03*
X1470197D03*
X1475197Y8012D03*
X1476378Y617441D03*
Y625315D03*
Y633189D03*
X1484252D03*
Y625315D03*
Y617441D03*
X1508661Y633189D03*
Y625315D03*
Y617441D03*
X1516535Y633189D03*
Y625315D03*
Y617441D03*
X1532283Y633189D03*
Y625315D03*
Y617441D03*
X1540157Y633189D03*
Y625315D03*
Y617441D03*
X1576280Y601693D03*
X1568406D03*
X1576280Y609567D03*
Y617441D03*
Y625315D03*
Y633189D03*
X1568406Y609567D03*
Y617441D03*
Y625315D03*
Y633189D03*
X1576280Y641063D03*
Y648937D03*
Y656811D03*
X1568406Y641063D03*
Y648937D03*
Y656811D03*
X1576280Y664685D03*
X1568406D03*
G54D45*
X1846142Y230433D03*
Y240433D03*
X1856772D03*
Y230433D03*
X1846142Y250433D03*
Y260433D03*
X1856772D03*
Y250433D03*
X1858957Y324213D03*
Y314213D03*
G54D38*
X825900Y382200D03*
X906900D03*
G54D41*
X1011017Y598187D03*
G54D40*
Y570042D03*
G54D25*
X207874Y639095D03*
X1524409D03*
G54D14*
X47244Y17716D03*
Y330708D03*
X279528Y53148D03*
X314961Y561023D03*
X393702Y344488D03*
X748032Y64961D03*
Y344488D03*
X984252Y64961D03*
Y344488D03*
X1338584D03*
X1417324Y561023D03*
X1452756Y53149D03*
X1685040Y17716D03*
Y330708D03*
X1799212Y96457D03*
Y478346D03*
G54D27*
X287402Y628465D03*
X263780Y659961D03*
X1468504Y628465D03*
X1444882Y659961D03*
G54D10*
X19685Y-774040D03*
Y766166D03*
X240866Y15512D03*
X300866Y10197D03*
X566575Y463701D03*
D03*
D03*
X1431417Y15512D03*
X1491417Y10197D03*
X1854331Y-774040D03*
Y766166D03*
G54D46*
X1851457Y220433D03*
X1856772Y360433D03*
G54D23*
X231600Y81000D03*
X1212478Y300181D03*
X1529100Y78500D03*
G54D35*
X822087Y88484D03*
Y313484D03*
X940197Y88484D03*
Y313484D03*
G54D22*
X192126Y656811D03*
Y648937D03*
Y664685D03*
X215748Y656811D03*
Y648937D03*
X223622Y656811D03*
Y648937D03*
X200000Y656811D03*
Y648937D03*
X215748Y664685D03*
X223622D03*
X200000D03*
X255906Y648937D03*
X248032D03*
X255906Y656811D03*
X248032D03*
X255906Y664685D03*
X248032D03*
X279528Y648937D03*
X271654D03*
X279528Y656811D03*
X271654D03*
X279528Y664685D03*
X271654D03*
X303150Y648937D03*
X295276D03*
X303150Y656811D03*
X295276D03*
X303150Y664685D03*
X295276D03*
X1437008Y648937D03*
X1429134D03*
X1437008Y656811D03*
X1429134D03*
X1437008Y664685D03*
X1429134D03*
X1460630Y648937D03*
X1452756D03*
X1460630Y656811D03*
X1452756D03*
X1460630Y664685D03*
X1452756D03*
X1484252Y648937D03*
X1476378D03*
X1484252Y656811D03*
X1476378D03*
X1484252Y664685D03*
X1476378D03*
X1508661Y656811D03*
Y648937D03*
X1516535Y656811D03*
Y648937D03*
X1508661Y664685D03*
X1516535D03*
X1532283Y656811D03*
Y648937D03*
X1540157Y656811D03*
Y648937D03*
X1532283Y664685D03*
X1540157D03*
G54D26*
X250866Y20827D03*
X284646Y18012D03*
X260866Y20827D03*
X1451417D03*
X1441417D03*
X1475197Y18012D03*
G54D24*
X225829Y103412D03*
Y99503D03*
X225953Y95780D03*
X225891Y92305D03*
X229829Y103412D03*
X233329D03*
X237329D03*
X229829Y99503D03*
X233329D03*
X237329D03*
X229953Y95780D03*
X233453D03*
X237453D03*
X229891Y92305D03*
X233391D03*
X237391D03*
X622288Y235790D03*
X624788D03*
X1635000Y152925D03*
X1733600Y397500D03*
X1731100D03*
X1728600D03*
G54D11*
X3018Y23930D03*
X10493Y5830D03*
X3018Y43930D03*
Y83930D03*
Y63930D03*
Y103930D03*
Y143930D03*
Y123930D03*
Y163930D03*
Y203930D03*
Y183930D03*
Y223930D03*
Y263930D03*
Y243930D03*
Y283930D03*
Y323930D03*
Y303930D03*
Y343930D03*
Y383930D03*
Y363930D03*
Y403930D03*
Y443930D03*
Y423930D03*
Y463930D03*
Y503930D03*
Y483930D03*
Y523930D03*
Y563930D03*
Y543930D03*
Y583930D03*
X15642Y619715D03*
X3018Y603930D03*
X30709Y3014D03*
X35455Y620194D03*
X75455D03*
X55455D03*
X81406Y3042D03*
X101406D03*
X95455Y620194D03*
X121406Y3042D03*
X137355Y120500D03*
X114923Y623982D03*
X124901Y640105D03*
X161406Y3042D03*
X141406D03*
X154778Y672779D03*
X181406Y3042D03*
X194778Y672779D03*
X174778D03*
X201406Y3042D03*
X221406D03*
X205061Y85500D03*
Y79000D03*
Y75000D03*
Y71500D03*
Y67500D03*
Y89500D03*
Y93000D03*
Y97000D03*
X200600Y109059D03*
X205100Y123000D03*
X214778Y672779D03*
X254778D03*
X234778D03*
X274778D03*
X314766Y39211D03*
X317766D03*
X311956Y651522D03*
X294778Y672779D03*
X323766Y39211D03*
X320766D03*
X324000Y77000D03*
X321000Y63000D03*
X345412Y435017D03*
Y455017D03*
Y475017D03*
Y495017D03*
Y515017D03*
Y535017D03*
Y555017D03*
Y575017D03*
Y595017D03*
X342119Y613510D03*
X331285Y620008D03*
X369192Y38417D03*
X372192D03*
X378192D03*
X375192D03*
X362127Y406608D03*
X350024Y418335D03*
X408100Y180100D03*
Y224500D03*
X399680Y402510D03*
X379680D03*
X419680D03*
X459680D03*
X439680D03*
X498923Y37456D03*
X495923D03*
X492923D03*
X489923D03*
X479680Y402510D03*
X501923Y37456D03*
X504923D03*
X510923D03*
X507923D03*
X528084Y68900D03*
Y65900D03*
X525084Y68900D03*
Y65900D03*
X522084Y68900D03*
Y65900D03*
X525084Y113300D03*
Y110300D03*
X522084Y113300D03*
Y110300D03*
X528084Y113300D03*
Y110300D03*
X525084Y157700D03*
Y154700D03*
X522084Y157700D03*
Y154700D03*
Y199100D03*
Y202100D03*
X525084Y199100D03*
Y202100D03*
X522084Y243500D03*
Y246500D03*
X525084Y243500D03*
Y246500D03*
X528084Y243500D03*
Y246500D03*
Y290900D03*
Y287900D03*
X525084D03*
Y290900D03*
X522084D03*
Y287900D03*
X499680Y402510D03*
X519680D03*
X531084Y68900D03*
Y65900D03*
Y290900D03*
Y287900D03*
X539680Y402510D03*
X559680D03*
X579680D03*
X601675Y305575D03*
X619680Y402510D03*
X599680D03*
X645784Y43500D03*
X648784D03*
X645784Y40500D03*
X648784D03*
X645784Y99000D03*
X648784D03*
X645784Y96000D03*
X648784D03*
X641000Y261500D03*
X639680Y402510D03*
X651784Y43500D03*
Y40500D03*
X657784D03*
X654784D03*
X657784Y43500D03*
X654784D03*
X651784Y99000D03*
Y96000D03*
X657784D03*
X654784D03*
X657784Y99000D03*
X654784D03*
X659000Y284000D03*
X671000Y315760D03*
X668000Y311500D03*
X663500D03*
X657500Y326925D03*
X659680Y402510D03*
X679680D03*
X693863Y189760D03*
X688900Y184260D03*
X704200Y206569D03*
X699680Y402510D03*
X736554Y131056D03*
Y128056D03*
X739554Y131056D03*
Y128056D03*
X742554D03*
X732100Y185000D03*
X729100D03*
X726100D03*
X720100D03*
X723100D03*
X726100Y188000D03*
X729100D03*
X732100D03*
X723100D03*
X720100D03*
X726000Y231500D03*
X729000D03*
X723000D03*
X720000D03*
X732000D03*
Y228500D03*
X720000D03*
X723000D03*
X726000D03*
X729000D03*
X719500Y315500D03*
X734500Y310575D03*
X739680Y402510D03*
X719680D03*
X742554Y131056D03*
X749600Y185000D03*
X752600D03*
X755600D03*
X758600D03*
X746600Y188000D03*
X758600D03*
X755600D03*
X752600D03*
X749600D03*
X746600Y185000D03*
X758500Y231500D03*
X746500D03*
X755500D03*
X752500D03*
X749500D03*
X746500Y228500D03*
X755500D03*
X752500D03*
X749500D03*
X758500D03*
X759680Y402510D03*
X779680D03*
X799680D03*
X819680D03*
X839680D03*
X859680D03*
X880500Y369500D03*
X879680Y402510D03*
X919680D03*
X899680D03*
X939680D03*
X983500Y185000D03*
Y188000D03*
X980500Y185000D03*
X974500D03*
X977500D03*
X980500Y188000D03*
X977500D03*
X974500D03*
Y231500D03*
X977500D03*
X983500D03*
X980500D03*
X983500Y228500D03*
X980500D03*
X977500D03*
X974500D03*
X959680Y402510D03*
X979680D03*
X990954Y131056D03*
Y128056D03*
X993954Y131056D03*
Y128056D03*
X996954D03*
Y131056D03*
X986500Y185000D03*
Y188000D03*
X1004000Y185000D03*
X1001000Y188000D03*
X1004000D03*
X1007000Y185000D03*
X1010000D03*
X1013000D03*
Y188000D03*
X1010000D03*
X1007000D03*
X1001000Y185000D03*
X1004000Y231500D03*
X1007000D03*
X1010000D03*
X1001000D03*
X986500D03*
X1013000D03*
X986500Y228500D03*
X1013000D03*
X1004000D03*
X1007000D03*
X1010000D03*
X1001000D03*
X999680Y402510D03*
X1039680D03*
X1019680D03*
X1074500Y43500D03*
Y99000D03*
X1059680Y402510D03*
X1077500Y43500D03*
Y40500D03*
X1074500D03*
X1080500D03*
X1083500D03*
X1086500D03*
X1080500Y43500D03*
X1083500D03*
X1086500D03*
X1077500Y99000D03*
Y96000D03*
X1074500D03*
X1080500D03*
X1083500D03*
X1086500D03*
X1080500Y99000D03*
X1083500D03*
X1086500D03*
X1101500Y268500D03*
X1079680Y402510D03*
X1099680D03*
X1118500Y283000D03*
X1106000Y364500D03*
X1112500Y364700D03*
X1122000Y366240D03*
X1119680Y402510D03*
X1155366Y38982D03*
X1152366D03*
X1158366D03*
X1161366D03*
X1143500Y251500D03*
X1141600Y305161D03*
X1154600Y321050D03*
X1143100Y322500D03*
Y320000D03*
X1147000Y342500D03*
X1135000Y366500D03*
X1139000D03*
X1159680Y402510D03*
X1139680D03*
X1176100Y105800D03*
Y108800D03*
X1182100Y105800D03*
Y108800D03*
X1179100D03*
Y105800D03*
X1176100Y111800D03*
Y114800D03*
Y117800D03*
X1182100Y111800D03*
Y114800D03*
Y117800D03*
X1179100D03*
Y114800D03*
Y111800D03*
X1176100Y126800D03*
Y123800D03*
Y120800D03*
X1182100Y126800D03*
Y123800D03*
Y120800D03*
X1179100D03*
Y123800D03*
Y126800D03*
X1176100Y239000D03*
X1171600Y238000D03*
X1179100Y239000D03*
X1182100D03*
X1176100Y254000D03*
Y251000D03*
Y248000D03*
Y245000D03*
Y257000D03*
Y260000D03*
Y242000D03*
X1171600Y241500D03*
X1179100Y242000D03*
Y260000D03*
Y257000D03*
Y245000D03*
Y248000D03*
Y251000D03*
Y254000D03*
X1182100D03*
Y251000D03*
Y248000D03*
Y245000D03*
Y257000D03*
Y260000D03*
Y242000D03*
X1165575Y340500D03*
X1171700Y349900D03*
X1178500Y368740D03*
X1179680Y402510D03*
X1223866Y38482D03*
X1220866D03*
X1225930Y359148D03*
X1199680Y402510D03*
X1219680D03*
X1226866Y38482D03*
X1229866D03*
X1237200Y205100D03*
Y202100D03*
Y199100D03*
X1240200D03*
Y202100D03*
Y205100D03*
X1234200Y249500D03*
Y246500D03*
Y243500D03*
X1237200Y249500D03*
Y246500D03*
Y243500D03*
X1240200D03*
Y246500D03*
Y249500D03*
Y293900D03*
Y290900D03*
Y287900D03*
X1237200D03*
Y290900D03*
Y293900D03*
X1234200Y287900D03*
Y290900D03*
Y293900D03*
X1231200D03*
Y290900D03*
Y287900D03*
X1242930Y359148D03*
Y356148D03*
X1245930Y359148D03*
Y356148D03*
X1248930Y359148D03*
Y356148D03*
X1231930D03*
Y359148D03*
X1228930Y356148D03*
Y359148D03*
X1225930Y356148D03*
X1253930Y379648D03*
X1250930D03*
X1247930D03*
X1239680Y402510D03*
X1264366Y38482D03*
X1261366D03*
X1267366D03*
X1270366D03*
X1260340Y359284D03*
Y356284D03*
X1263340Y359284D03*
Y356284D03*
X1266340Y359284D03*
Y356284D03*
X1286113Y378312D03*
X1265340Y379784D03*
X1268340D03*
X1271340D03*
X1259680Y402510D03*
X1279680D03*
X1313366Y38482D03*
X1307366D03*
X1310366D03*
X1286113Y375312D03*
X1289113Y378312D03*
Y375312D03*
X1292113Y378312D03*
Y375312D03*
Y372312D03*
X1289113D03*
X1299680Y402510D03*
X1316366Y38482D03*
X1339680Y402510D03*
X1319680D03*
X1355310Y38893D03*
X1352310D03*
X1349310D03*
X1358310D03*
X1355100Y160000D03*
X1355000Y204400D03*
X1359620Y402940D03*
X1386882Y434539D03*
Y454539D03*
Y474539D03*
Y494539D03*
Y514539D03*
Y534539D03*
Y554539D03*
Y574539D03*
Y594539D03*
X1389643Y612723D03*
X1403035Y620181D03*
X1422310Y40481D03*
X1419310D03*
X1416310D03*
X1425310D03*
X1420335Y635388D03*
Y655388D03*
X1428754Y670547D03*
X1445829Y672778D03*
X1465829D03*
X1490000Y84000D03*
X1485829Y672778D03*
X1508460Y3003D03*
X1527100Y108500D03*
X1505829Y672778D03*
X1525829D03*
X1548460Y3003D03*
X1528460D03*
X1531600Y96941D03*
X1545829Y672778D03*
X1588460Y3003D03*
X1568460D03*
X1565829Y672778D03*
X1585829D03*
X1608460Y3003D03*
X1609100Y85500D03*
Y82000D03*
X1606100Y85500D03*
Y82000D03*
X1609100Y69500D03*
Y66000D03*
Y62500D03*
X1606100Y69500D03*
Y66000D03*
Y62500D03*
X1602100Y85500D03*
Y82000D03*
Y69500D03*
Y66000D03*
Y62500D03*
X1594930Y115000D03*
X1614100Y110000D03*
Y115000D03*
X1609100Y89000D03*
X1606100D03*
X1602100D03*
X1614100Y120000D03*
Y130000D03*
X1613527Y627220D03*
X1607226Y650448D03*
X1602599Y667628D03*
X1648460Y3003D03*
X1628460D03*
X1629870Y104240D03*
X1647837Y121812D03*
X1638707Y132954D03*
X1623100Y172500D03*
Y178000D03*
X1631585Y188777D03*
X1628658Y620261D03*
X1648675Y620226D03*
X1662000Y106000D03*
X1649197Y132915D03*
X1650990Y122034D03*
X1667000Y138000D03*
X1649500Y173398D03*
X1668075Y189500D03*
X1679176Y194760D03*
X1652600Y212000D03*
X1668675Y620226D03*
X1708460Y3003D03*
X1702525Y129500D03*
X1685976Y148000D03*
Y164500D03*
Y159000D03*
Y153500D03*
Y175500D03*
Y170000D03*
X1701100Y178500D03*
X1685976Y181000D03*
X1702075Y205500D03*
X1688692Y620191D03*
X1708692D03*
X1729255Y25347D03*
Y45347D03*
X1732786Y58461D03*
X1729411Y143661D03*
X1720100Y179500D03*
X1729411Y159161D03*
X1733500Y173760D03*
X1712000Y153000D03*
X1738740Y191500D03*
X1729000Y183500D03*
X1724824Y205276D03*
X1711025Y187000D03*
X1729275Y562751D03*
Y542751D03*
Y582751D03*
Y602751D03*
X1753635Y69037D03*
X1764000Y107000D03*
X1763500Y113000D03*
X1763075Y178900D03*
X1767075Y155484D03*
X1769476Y168500D03*
X1754260Y187260D03*
X1768000D03*
X1746000Y191240D03*
X1751289Y345227D03*
X1747416Y351817D03*
X1747235Y355989D03*
Y359564D03*
Y363689D03*
Y367264D03*
Y371389D03*
Y374964D03*
X1755454Y515746D03*
X1793635Y69037D03*
X1773635D03*
X1773500Y121000D03*
X1772500Y174000D03*
X1770075Y181500D03*
X1776100Y361500D03*
Y371500D03*
Y368500D03*
X1776140Y364405D03*
X1775454Y515746D03*
X1813635Y69037D03*
X1815454Y515746D03*
X1853635Y69037D03*
X1833635D03*
X1844500Y416500D03*
X1847500Y437000D03*
X1835454Y515746D03*
X1855509Y515697D03*
X1871008Y117112D03*
X1871009Y93913D03*
X1871008Y137112D03*
Y177112D03*
Y157112D03*
Y197112D03*
Y237112D03*
Y217112D03*
Y257112D03*
Y297112D03*
Y277112D03*
Y317112D03*
Y357112D03*
Y337112D03*
Y377112D03*
Y417112D03*
Y397112D03*
Y437112D03*
Y477112D03*
Y457112D03*
Y497112D03*
G54D33*
X802087Y145984D03*
X792087D03*
X802087Y135984D03*
X792087D03*
X802087Y180984D03*
X792087D03*
X802087Y170984D03*
X792087D03*
X802087Y230984D03*
X792087D03*
X802087Y220984D03*
X792087D03*
X802087Y265984D03*
X792087D03*
X802087Y255984D03*
X792087D03*
X822087Y145984D03*
X812087D03*
X822087Y135984D03*
X812087D03*
X822087Y180984D03*
X812087D03*
X822087Y170984D03*
X812087D03*
X822087Y230984D03*
X812087D03*
X822087Y220984D03*
X812087D03*
X822087Y265984D03*
X812087D03*
X822087Y255984D03*
X812087D03*
X920197Y145984D03*
X910197D03*
X920197Y135984D03*
X910197D03*
X920197Y180984D03*
X910197D03*
X920197Y170984D03*
X910197D03*
X920197Y230984D03*
X910197D03*
X920197Y220984D03*
X910197D03*
X920197Y265984D03*
X910197D03*
X920197Y255984D03*
X910197D03*
X940197Y145984D03*
X930197D03*
X940197Y135984D03*
X930197D03*
X940197Y180984D03*
X930197D03*
X940197Y170984D03*
X930197D03*
X940197Y230984D03*
X930197D03*
X940197Y220984D03*
X930197D03*
X940197Y265984D03*
X930197D03*
X940197Y255984D03*
X930197D03*
G54D36*
X822087Y88484D03*
Y313484D03*
X940197Y88484D03*
Y313484D03*
G54D16*
X59055Y236614D03*
Y411594D03*
X1673228Y236614D03*
Y411614D03*
G54D44*
X1835739Y99212D03*
X1835738Y481693D03*
G54D12*
X32284Y541339D03*
X59055Y498032D03*
X1673228D03*
X1700000Y541339D03*
G54D39*
X866400Y372200D03*
G54D30*
X668314Y570042D03*
G54D32*
X668420Y598187D03*
%LPC*%
G75*
G54D19*
X166785Y200472D03*
Y280472D03*
Y360472D03*
Y440472D03*
Y520472D03*
X243785Y200472D03*
Y280472D03*
Y360472D03*
Y440472D03*
Y520472D03*
X1488500Y200472D03*
Y280472D03*
Y360472D03*
Y440472D03*
Y520472D03*
X1565500Y200472D03*
Y280472D03*
Y360472D03*
Y440472D03*
Y520472D03*
G54D48*
G01X169956Y197301D02*
X166785Y200472D01*
G01D02*
X163614Y203643D01*
G01X169956D02*
X166785Y200472D01*
G01D02*
X163614Y197301D01*
G01X169956Y277301D02*
X166785Y280472D01*
G01D02*
X163614Y283643D01*
G01X169956D02*
X166785Y280472D01*
G01D02*
X163614Y277301D01*
G01X166785Y360472D02*
X163614Y357301D01*
G01X169956D02*
X166785Y360472D01*
G01D02*
X163614Y363643D01*
G01X169956D02*
X166785Y360472D01*
G01X169956Y437301D02*
X166785Y440472D01*
G01D02*
X163614Y443643D01*
G01X169956D02*
X166785Y440472D01*
G01D02*
X163614Y437301D01*
G01X166785Y520472D02*
X163614Y517301D01*
G01X169956Y523643D02*
X166785Y520472D01*
G01D02*
X163614Y523643D01*
G01X169956Y517301D02*
X166785Y520472D01*
G01X246956Y197301D02*
X243785Y200472D01*
G01D02*
X240614Y203643D01*
G01X246956D02*
X243785Y200472D01*
G01D02*
X240614Y197301D01*
G01X246956Y277301D02*
X243785Y280472D01*
G01D02*
X240614Y283643D01*
G01X246956D02*
X243785Y280472D01*
G01D02*
X240614Y277301D01*
G01X246956Y357301D02*
X243785Y360472D01*
G01D02*
X240614Y363643D01*
G01X246956D02*
X243785Y360472D01*
G01D02*
X240614Y357301D01*
G01X246956Y437301D02*
X243785Y440472D01*
G01D02*
X240614Y443643D01*
G01X246956D02*
X243785Y440472D01*
G01D02*
X240614Y437301D01*
G01X246956Y517301D02*
X243785Y520472D01*
G01D02*
X240614Y523643D01*
G01X246956D02*
X243785Y520472D01*
G01D02*
X240614Y517301D01*
G01X1491671Y197301D02*
X1488500Y200472D01*
G01D02*
X1485329Y203643D01*
G01X1491671D02*
X1488500Y200472D01*
G01D02*
X1485329Y197301D01*
G01X1491671Y277301D02*
X1488500Y280472D01*
G01D02*
X1485329Y283643D01*
G01X1491671D02*
X1488500Y280472D01*
G01D02*
X1485329Y277301D01*
G01X1491671Y357301D02*
X1488500Y360472D01*
G01D02*
X1485329Y363643D01*
G01X1491671D02*
X1488500Y360472D01*
G01D02*
X1485329Y357301D01*
G01X1491671Y437301D02*
X1488500Y440472D01*
G01D02*
X1485329Y443643D01*
G01X1491671D02*
X1488500Y440472D01*
G01D02*
X1485329Y437301D01*
G01X1491671Y517301D02*
X1488500Y520472D01*
G01D02*
X1485329Y523643D01*
G01X1491671D02*
X1488500Y520472D01*
G01D02*
X1485329Y517301D01*
G01X1568671Y197301D02*
X1565500Y200472D01*
G01D02*
X1562329Y203643D01*
G01X1568671D02*
X1565500Y200472D01*
G01D02*
X1562329Y197301D01*
G01X1568671Y277301D02*
X1565500Y280472D01*
G01D02*
X1562329Y283643D01*
G01X1568671D02*
X1565500Y280472D01*
G01D02*
X1562329Y277301D01*
G01X1568671Y357301D02*
X1565500Y360472D01*
G01D02*
X1562329Y363643D01*
G01X1568671D02*
X1565500Y360472D01*
G01D02*
X1562329Y357301D01*
G01X1568671Y437301D02*
X1565500Y440472D01*
G01D02*
X1562329Y443643D01*
G01X1568671D02*
X1565500Y440472D01*
G01D02*
X1562329Y437301D01*
G01X1568671Y517301D02*
X1565500Y520472D01*
G01D02*
X1562329Y523643D01*
G01X1568671D02*
X1565500Y520472D01*
G01D02*
X1562329Y517301D01*
G54D49*
G01X-457143Y-1211429D02*
Y2242857D01*
X4308572D01*
Y-1211429D01*
X-457143D01*
G01X37000Y-995000D02*
Y-1070000D01*
X537000D01*
Y-995000D01*
X37000D01*
G01X49000Y-1060000D02*
Y-1065000D01*
G01X47543Y-1060000D02*
X50457D01*
G01X55367Y-1065000D02*
X52833D01*
Y-1060000D01*
X55367D01*
G01X54353Y-1062417D02*
X52833D01*
G01X57933Y-1060000D02*
Y-1065000D01*
X60467D01*
G01X64300Y-1065167D02*
X64173Y-1065083D01*
Y-1064917D01*
X64300Y-1064833D01*
X64427Y-1064917D01*
Y-1065083D01*
X64300Y-1065167D01*
G01Y-1062917D02*
X64173Y-1062833D01*
Y-1062667D01*
X64300Y-1062583D01*
X64427Y-1062667D01*
Y-1062833D01*
X64300Y-1062917D01*
G01X69083Y-1066667D02*
X68450Y-1065833D01*
X68133Y-1065000D01*
Y-1061667D01*
X68450Y-1060833D01*
X69083Y-1060000D01*
G01X74500D02*
X73993Y-1060167D01*
X73613Y-1060583D01*
X73360Y-1061083D01*
X73170Y-1061750D01*
X73107Y-1062500D01*
X73170Y-1063250D01*
X73360Y-1063917D01*
X73613Y-1064417D01*
X73993Y-1064833D01*
X74500Y-1065000D01*
X75007Y-1064833D01*
X75387Y-1064417D01*
X75640Y-1063917D01*
X75830Y-1063250D01*
X75893Y-1062500D01*
X75830Y-1061750D01*
X75640Y-1061083D01*
X75387Y-1060583D01*
X75007Y-1060167D01*
X74500Y-1060000D01*
G01X78207Y-1064000D02*
X78587Y-1064583D01*
X79093Y-1064917D01*
X79663Y-1065000D01*
X80170Y-1064917D01*
X80677Y-1064500D01*
X80993Y-1064000D01*
X81057Y-1063500D01*
X80930Y-1062917D01*
X80487Y-1062500D01*
X80043Y-1062333D01*
X79473D01*
G01X80043D02*
X80423Y-1062083D01*
X80740Y-1061667D01*
X80867Y-1061167D01*
X80740Y-1060667D01*
X80423Y-1060250D01*
X79853Y-1060000D01*
X79283Y-1060083D01*
X78713Y-1060417D01*
G01X85017Y-1066667D02*
X85650Y-1065833D01*
X85967Y-1065000D01*
Y-1061667D01*
X85650Y-1060833D01*
X85017Y-1060000D01*
G01X88407Y-1064000D02*
X88787Y-1064583D01*
X89293Y-1064917D01*
X89863Y-1065000D01*
X90370Y-1064917D01*
X90877Y-1064500D01*
X91193Y-1064000D01*
X91257Y-1063500D01*
X91130Y-1062917D01*
X90687Y-1062500D01*
X90243Y-1062333D01*
X89673D01*
G01X90243D02*
X90623Y-1062083D01*
X90940Y-1061667D01*
X91067Y-1061167D01*
X90940Y-1060667D01*
X90623Y-1060250D01*
X90053Y-1060000D01*
X89483Y-1060083D01*
X88913Y-1060417D01*
G01X93697Y-1060833D02*
X94077Y-1060333D01*
X94520Y-1060083D01*
X95027Y-1060000D01*
X95660Y-1060167D01*
X96103Y-1060583D01*
X96230Y-1061083D01*
X96167Y-1061583D01*
X95913Y-1062000D01*
X94647Y-1062833D01*
X94077Y-1063417D01*
X93697Y-1064250D01*
X93570Y-1065000D01*
X96230D01*
G01X99873D02*
X100000Y-1063917D01*
X100190Y-1063000D01*
X100443Y-1062167D01*
X100760Y-1061250D01*
X101267Y-1060000D01*
X98733D01*
G01X104277Y-1063333D02*
X105923D01*
G01X108997Y-1060833D02*
X109377Y-1060333D01*
X109820Y-1060083D01*
X110327Y-1060000D01*
X110960Y-1060167D01*
X111403Y-1060583D01*
X111530Y-1061083D01*
X111467Y-1061583D01*
X111213Y-1062000D01*
X109947Y-1062833D01*
X109377Y-1063417D01*
X108997Y-1064250D01*
X108870Y-1065000D01*
X111530D01*
G01X113907Y-1064000D02*
X114287Y-1064583D01*
X114793Y-1064917D01*
X115363Y-1065000D01*
X115870Y-1064917D01*
X116377Y-1064500D01*
X116693Y-1064000D01*
X116757Y-1063500D01*
X116630Y-1062917D01*
X116187Y-1062500D01*
X115743Y-1062333D01*
X115173D01*
G01X115743D02*
X116123Y-1062083D01*
X116440Y-1061667D01*
X116567Y-1061167D01*
X116440Y-1060667D01*
X116123Y-1060250D01*
X115553Y-1060000D01*
X114983Y-1060083D01*
X114413Y-1060417D01*
G01X121160Y-1065000D02*
Y-1060000D01*
X118817Y-1063583D01*
X121983D01*
G01X124107Y-1064250D02*
X124487Y-1064667D01*
X124930Y-1064917D01*
X125500Y-1065000D01*
X126070Y-1064833D01*
X126513Y-1064500D01*
X126830Y-1063917D01*
X126893Y-1063250D01*
X126767Y-1062583D01*
X126450Y-1062167D01*
X126007Y-1061833D01*
X125563Y-1061750D01*
X125120Y-1061833D01*
X124550Y-1062167D01*
X124740Y-1060000D01*
X126450D01*
G01X134497Y-1065000D02*
Y-1060000D01*
X136903D01*
G01X136017Y-1062417D02*
X134497D01*
G01X139217Y-1065000D02*
X140800Y-1060000D01*
X142383Y-1065000D01*
G01X141813Y-1063250D02*
X139787D01*
G01X144570Y-1065000D02*
X147230Y-1060000D01*
G01X144570D02*
X147230Y-1065000D01*
G01X151000Y-1065167D02*
X150873Y-1065083D01*
Y-1064917D01*
X151000Y-1064833D01*
X151127Y-1064917D01*
Y-1065083D01*
X151000Y-1065167D01*
G01Y-1062917D02*
X150873Y-1062833D01*
Y-1062667D01*
X151000Y-1062583D01*
X151127Y-1062667D01*
Y-1062833D01*
X151000Y-1062917D01*
G01X155783Y-1066667D02*
X155150Y-1065833D01*
X154833Y-1065000D01*
Y-1061667D01*
X155150Y-1060833D01*
X155783Y-1060000D01*
G01X161200D02*
X160693Y-1060167D01*
X160313Y-1060583D01*
X160060Y-1061083D01*
X159870Y-1061750D01*
X159807Y-1062500D01*
X159870Y-1063250D01*
X160060Y-1063917D01*
X160313Y-1064417D01*
X160693Y-1064833D01*
X161200Y-1065000D01*
X161707Y-1064833D01*
X162087Y-1064417D01*
X162340Y-1063917D01*
X162530Y-1063250D01*
X162593Y-1062500D01*
X162530Y-1061750D01*
X162340Y-1061083D01*
X162087Y-1060583D01*
X161707Y-1060167D01*
X161200Y-1060000D01*
G01X164907Y-1064000D02*
X165287Y-1064583D01*
X165793Y-1064917D01*
X166363Y-1065000D01*
X166870Y-1064917D01*
X167377Y-1064500D01*
X167693Y-1064000D01*
X167757Y-1063500D01*
X167630Y-1062917D01*
X167187Y-1062500D01*
X166743Y-1062333D01*
X166173D01*
G01X166743D02*
X167123Y-1062083D01*
X167440Y-1061667D01*
X167567Y-1061167D01*
X167440Y-1060667D01*
X167123Y-1060250D01*
X166553Y-1060000D01*
X165983Y-1060083D01*
X165413Y-1060417D01*
G01X171717Y-1066667D02*
X172350Y-1065833D01*
X172667Y-1065000D01*
Y-1061667D01*
X172350Y-1060833D01*
X171717Y-1060000D01*
G01X175107Y-1064000D02*
X175487Y-1064583D01*
X175993Y-1064917D01*
X176563Y-1065000D01*
X177070Y-1064917D01*
X177577Y-1064500D01*
X177893Y-1064000D01*
X177957Y-1063500D01*
X177830Y-1062917D01*
X177387Y-1062500D01*
X176943Y-1062333D01*
X176373D01*
G01X176943D02*
X177323Y-1062083D01*
X177640Y-1061667D01*
X177767Y-1061167D01*
X177640Y-1060667D01*
X177323Y-1060250D01*
X176753Y-1060000D01*
X176183Y-1060083D01*
X175613Y-1060417D01*
G01X180523Y-1064417D02*
X180967Y-1064833D01*
X181473Y-1065000D01*
X181980Y-1064833D01*
X182423Y-1064333D01*
X182740Y-1063583D01*
X182867Y-1062833D01*
Y-1061917D01*
X182740Y-1061167D01*
X182423Y-1060500D01*
X182043Y-1060167D01*
X181600Y-1060000D01*
X181093Y-1060167D01*
X180713Y-1060500D01*
X180460Y-1061000D01*
X180333Y-1061667D01*
X180460Y-1062250D01*
X180777Y-1062833D01*
X181157Y-1063167D01*
X181600Y-1063250D01*
X182107Y-1063083D01*
X182487Y-1062667D01*
X182867Y-1061917D01*
G01X186573Y-1065000D02*
X186700Y-1063917D01*
X186890Y-1063000D01*
X187143Y-1062167D01*
X187460Y-1061250D01*
X187967Y-1060000D01*
X185433D01*
G01X190977Y-1063333D02*
X192623D01*
G01X195507Y-1064000D02*
X195887Y-1064583D01*
X196393Y-1064917D01*
X196963Y-1065000D01*
X197470Y-1064917D01*
X197977Y-1064500D01*
X198293Y-1064000D01*
X198357Y-1063500D01*
X198230Y-1062917D01*
X197787Y-1062500D01*
X197343Y-1062333D01*
X196773D01*
G01X197343D02*
X197723Y-1062083D01*
X198040Y-1061667D01*
X198167Y-1061167D01*
X198040Y-1060667D01*
X197723Y-1060250D01*
X197153Y-1060000D01*
X196583Y-1060083D01*
X196013Y-1060417D01*
G01X200797Y-1062917D02*
X201240Y-1062333D01*
X201620Y-1062000D01*
X202127Y-1061833D01*
X202570Y-1062000D01*
X202887Y-1062333D01*
X203140Y-1062833D01*
X203203Y-1063417D01*
X203140Y-1063917D01*
X202887Y-1064417D01*
X202507Y-1064833D01*
X202063Y-1065000D01*
X201557Y-1064833D01*
X201113Y-1064333D01*
X200860Y-1063583D01*
X200797Y-1062750D01*
X200923Y-1061667D01*
X201113Y-1061083D01*
X201430Y-1060500D01*
X201873Y-1060083D01*
X202317Y-1060000D01*
X202760Y-1060167D01*
X203077Y-1060583D01*
G01X207100Y-1065000D02*
Y-1060000D01*
X206340Y-1061000D01*
G01Y-1065000D02*
X207860D01*
G01X212960D02*
Y-1060000D01*
X210617Y-1063583D01*
X213783D01*
G01X232000Y-995000D02*
Y-1070000D01*
G01Y-1045000D02*
X335000D01*
Y-1020000D01*
G01X232000D02*
X335000D01*
G01X337000Y-995000D02*
Y-1070000D01*
G01X335000Y-995000D02*
Y-1070000D01*
G01X342507Y-1055000D02*
Y-1050000D01*
X343773D01*
X344280Y-1050250D01*
X344660Y-1050583D01*
X344977Y-1051083D01*
X345230Y-1051667D01*
X345293Y-1052500D01*
X345230Y-1053333D01*
X344977Y-1053917D01*
X344660Y-1054417D01*
X344280Y-1054750D01*
X343773Y-1055000D01*
X342507D01*
G01X347417D02*
X349000Y-1050000D01*
X350583Y-1055000D01*
G01X350013Y-1053250D02*
X347987D01*
G01X354100Y-1050000D02*
Y-1055000D01*
G01X352643Y-1050000D02*
X355557D01*
G01X360467Y-1055000D02*
X357933D01*
Y-1050000D01*
X360467D01*
G01X359453Y-1052417D02*
X357933D01*
G01X364300Y-1055167D02*
X364173Y-1055083D01*
Y-1054917D01*
X364300Y-1054833D01*
X364427Y-1054917D01*
Y-1055083D01*
X364300Y-1055167D01*
G01Y-1052917D02*
X364173Y-1052833D01*
Y-1052667D01*
X364300Y-1052583D01*
X364427Y-1052667D01*
Y-1052833D01*
X364300Y-1052917D01*
G01X337000Y-1045000D02*
X537000D01*
G01X342633Y-1030000D02*
Y-1025000D01*
X344153D01*
X344660Y-1025250D01*
X345040Y-1025833D01*
X345167Y-1026500D01*
X345040Y-1027167D01*
X344723Y-1027667D01*
X344153Y-1027917D01*
X342633D01*
G01X347860Y-1030167D02*
X350140Y-1025000D01*
G01X352643Y-1030000D02*
Y-1025000D01*
X355557Y-1030000D01*
Y-1025000D01*
G01X359200Y-1030167D02*
X359073Y-1030083D01*
Y-1029917D01*
X359200Y-1029833D01*
X359327Y-1029917D01*
Y-1030083D01*
X359200Y-1030167D01*
G01Y-1027917D02*
X359073Y-1027833D01*
Y-1027667D01*
X359200Y-1027583D01*
X359327Y-1027667D01*
Y-1027833D01*
X359200Y-1027917D01*
G01X342633Y-1005000D02*
Y-1000000D01*
X344153D01*
X344660Y-1000250D01*
X345040Y-1000833D01*
X345167Y-1001500D01*
X345040Y-1002167D01*
X344723Y-1002667D01*
X344153Y-1002917D01*
X342633D01*
G01X347733Y-1005000D02*
Y-1000000D01*
X349317D01*
X349823Y-1000250D01*
X350140Y-1000583D01*
X350267Y-1001250D01*
X350140Y-1001917D01*
X349760Y-1002333D01*
X349317Y-1002583D01*
X347733D01*
G01X349317D02*
X350267Y-1005000D01*
G01X354100D02*
X353593Y-1004917D01*
X353150Y-1004583D01*
X352770Y-1004083D01*
X352517Y-1003500D01*
X352390Y-1002833D01*
Y-1002167D01*
X352517Y-1001500D01*
X352770Y-1000917D01*
X353150Y-1000417D01*
X353593Y-1000083D01*
X354100Y-1000000D01*
X354607Y-1000083D01*
X355050Y-1000417D01*
X355430Y-1000917D01*
X355683Y-1001500D01*
X355810Y-1002167D01*
Y-1002833D01*
X355683Y-1003500D01*
X355430Y-1004083D01*
X355050Y-1004583D01*
X354607Y-1004917D01*
X354100Y-1005000D01*
G01X357933Y-1004000D02*
X358250Y-1004500D01*
X358630Y-1004833D01*
X359073Y-1005000D01*
X359580Y-1004833D01*
X359960Y-1004500D01*
X360340Y-1004000D01*
X360467Y-1003333D01*
Y-1000000D01*
G01X365567Y-1005000D02*
X363033D01*
Y-1000000D01*
X365567D01*
G01X364553Y-1002417D02*
X363033D01*
G01X370793Y-1000417D02*
X370413Y-1000167D01*
X369970Y-1000000D01*
X369463D01*
X368893Y-1000250D01*
X368450Y-1000667D01*
X368133Y-1001167D01*
X367880Y-1002000D01*
X367817Y-1002750D01*
X367943Y-1003500D01*
X368133Y-1004000D01*
X368513Y-1004500D01*
X368957Y-1004833D01*
X369400Y-1005000D01*
X369843D01*
X370287Y-1004833D01*
X370667Y-1004583D01*
X370983Y-1004250D01*
G01X374500Y-1000000D02*
Y-1005000D01*
G01X373043Y-1000000D02*
X375957D01*
G01X379600Y-1005167D02*
X379473Y-1005083D01*
Y-1004917D01*
X379600Y-1004833D01*
X379727Y-1004917D01*
Y-1005083D01*
X379600Y-1005167D01*
G01Y-1002917D02*
X379473Y-1002833D01*
Y-1002667D01*
X379600Y-1002583D01*
X379727Y-1002667D01*
Y-1002833D01*
X379600Y-1002917D01*
G01X337000Y-1020000D02*
X537000D01*
G01X452000Y-1045000D02*
Y-1070000D01*
G01X454633Y-1047500D02*
Y-1052500D01*
X457167D01*
G01X460240Y-1047500D02*
X461760D01*
G01X461000D02*
Y-1052500D01*
G01X460240D02*
X461760D01*
G01X466607Y-1049833D02*
X466860Y-1049583D01*
X467050Y-1049167D01*
X467177Y-1048583D01*
X467050Y-1048083D01*
X466797Y-1047750D01*
X466353Y-1047500D01*
X464643D01*
Y-1052500D01*
X466733D01*
X467177Y-1052167D01*
X467430Y-1051667D01*
X467557Y-1051083D01*
X467430Y-1050500D01*
X467050Y-1050000D01*
X466607Y-1049833D01*
X464643D01*
G01X471200Y-1052667D02*
X471073Y-1052583D01*
Y-1052417D01*
X471200Y-1052333D01*
X471327Y-1052417D01*
Y-1052583D01*
X471200Y-1052667D01*
G01Y-1050417D02*
X471073Y-1050333D01*
Y-1050167D01*
X471200Y-1050083D01*
X471327Y-1050167D01*
Y-1050333D01*
X471200Y-1050417D01*
G01X495000Y-1045000D02*
Y-1070000D01*
G01X498900Y-1047500D02*
Y-1052500D01*
G01X497443Y-1047500D02*
X500357D01*
G01X504000Y-1052500D02*
X503620Y-1052417D01*
X503240Y-1052083D01*
X502987Y-1051500D01*
X502860Y-1050833D01*
X502987Y-1050167D01*
X503240Y-1049583D01*
X503620Y-1049250D01*
X504000Y-1049167D01*
X504380Y-1049250D01*
X504760Y-1049583D01*
X505013Y-1050167D01*
X505077Y-1050833D01*
X505013Y-1051500D01*
X504760Y-1052083D01*
X504380Y-1052417D01*
X504000Y-1052500D01*
G01X509100D02*
X508720Y-1052417D01*
X508340Y-1052083D01*
X508087Y-1051500D01*
X507960Y-1050833D01*
X508087Y-1050167D01*
X508340Y-1049583D01*
X508720Y-1049250D01*
X509100Y-1049167D01*
X509480Y-1049250D01*
X509860Y-1049583D01*
X510113Y-1050167D01*
X510177Y-1050833D01*
X510113Y-1051500D01*
X509860Y-1052083D01*
X509480Y-1052417D01*
X509100Y-1052500D01*
G01X514200D02*
Y-1047500D01*
G01X519300Y-1052667D02*
X519173Y-1052583D01*
Y-1052417D01*
X519300Y-1052333D01*
X519427Y-1052417D01*
Y-1052583D01*
X519300Y-1052667D01*
G01Y-1050417D02*
X519173Y-1050333D01*
Y-1050167D01*
X519300Y-1050083D01*
X519427Y-1050167D01*
Y-1050333D01*
X519300Y-1050417D01*
G01X495000Y-1020000D02*
Y-1045000D01*
G01X497633Y-1027500D02*
Y-1022500D01*
X499217D01*
X499723Y-1022750D01*
X500040Y-1023083D01*
X500167Y-1023750D01*
X500040Y-1024417D01*
X499660Y-1024833D01*
X499217Y-1025083D01*
X497633D01*
G01X499217D02*
X500167Y-1027500D01*
G01X505267D02*
X502733D01*
Y-1022500D01*
X505267D01*
G01X504253Y-1024917D02*
X502733D01*
G01X507517Y-1022500D02*
X509100Y-1027500D01*
X510683Y-1022500D01*
G01X514200Y-1027667D02*
X514073Y-1027583D01*
Y-1027417D01*
X514200Y-1027333D01*
X514327Y-1027417D01*
Y-1027583D01*
X514200Y-1027667D01*
G01Y-1025417D02*
X514073Y-1025333D01*
Y-1025167D01*
X514200Y-1025083D01*
X514327Y-1025167D01*
Y-1025333D01*
X514200Y-1025417D01*
G01X503013Y-1073167D02*
X503120Y-1073042D01*
X503200Y-1072833D01*
X503253Y-1072542D01*
X503200Y-1072292D01*
X503093Y-1072125D01*
X502907Y-1072000D01*
X502187D01*
Y-1074500D01*
X503067D01*
X503253Y-1074333D01*
X503360Y-1074083D01*
X503413Y-1073792D01*
X503360Y-1073500D01*
X503200Y-1073250D01*
X503013Y-1073167D01*
X502187D01*
G01X505480Y-1074500D02*
Y-1072833D01*
G01Y-1073125D02*
X505373Y-1072958D01*
X505213Y-1072875D01*
X505027Y-1072833D01*
X504840Y-1072917D01*
X504680Y-1073083D01*
X504573Y-1073333D01*
X504520Y-1073667D01*
X504573Y-1074000D01*
X504680Y-1074250D01*
X504840Y-1074417D01*
X505027Y-1074500D01*
X505213Y-1074458D01*
X505373Y-1074333D01*
X505480Y-1074167D01*
G01X506800Y-1074208D02*
X506933Y-1074375D01*
X507120Y-1074500D01*
X507280D01*
X507440Y-1074417D01*
X507547Y-1074292D01*
X507600Y-1074125D01*
X507573Y-1073875D01*
X507467Y-1073750D01*
X506987Y-1073500D01*
X506880Y-1073208D01*
X506933Y-1073000D01*
X507040Y-1072875D01*
X507200Y-1072833D01*
X507360Y-1072875D01*
X507520Y-1073000D01*
G01X509000Y-1073375D02*
X509853D01*
X509773Y-1073083D01*
X509640Y-1072917D01*
X509453Y-1072833D01*
X509267Y-1072875D01*
X509107Y-1073000D01*
X509000Y-1073292D01*
X508947Y-1073542D01*
Y-1073792D01*
X509000Y-1074042D01*
X509133Y-1074292D01*
X509293Y-1074458D01*
X509480Y-1074500D01*
X509667Y-1074417D01*
X509853Y-1074167D01*
G01X511120Y-1074500D02*
Y-1072000D01*
G01Y-1073250D02*
X511253Y-1073000D01*
X511413Y-1072875D01*
X511573Y-1072833D01*
X511813Y-1072917D01*
X511973Y-1073083D01*
X512080Y-1073375D01*
Y-1073708D01*
X512027Y-1074042D01*
X511920Y-1074292D01*
X511733Y-1074458D01*
X511573Y-1074500D01*
X511413Y-1074458D01*
X511253Y-1074333D01*
X511120Y-1074125D01*
G01X513800Y-1074500D02*
X513640Y-1074458D01*
X513480Y-1074292D01*
X513373Y-1074000D01*
X513320Y-1073667D01*
X513373Y-1073333D01*
X513480Y-1073042D01*
X513640Y-1072875D01*
X513800Y-1072833D01*
X513960Y-1072875D01*
X514120Y-1073042D01*
X514227Y-1073333D01*
X514253Y-1073667D01*
X514227Y-1074000D01*
X514120Y-1074292D01*
X513960Y-1074458D01*
X513800Y-1074500D01*
G01X516480D02*
Y-1072833D01*
G01Y-1073125D02*
X516373Y-1072958D01*
X516213Y-1072875D01*
X516027Y-1072833D01*
X515840Y-1072917D01*
X515680Y-1073083D01*
X515573Y-1073333D01*
X515520Y-1073667D01*
X515573Y-1074000D01*
X515680Y-1074250D01*
X515840Y-1074417D01*
X516027Y-1074500D01*
X516213Y-1074458D01*
X516373Y-1074333D01*
X516480Y-1074167D01*
G01X517827Y-1074500D02*
Y-1072833D01*
G01Y-1073167D02*
X517960Y-1073000D01*
X518093Y-1072875D01*
X518280Y-1072833D01*
X518413Y-1072875D01*
X518573Y-1073000D01*
G01X520880Y-1072000D02*
Y-1074500D01*
G01Y-1074125D02*
X520773Y-1074333D01*
X520613Y-1074458D01*
X520427Y-1074500D01*
X520213Y-1074417D01*
X520053Y-1074208D01*
X519947Y-1073958D01*
X519920Y-1073667D01*
X519947Y-1073375D01*
X520053Y-1073125D01*
X520213Y-1072917D01*
X520427Y-1072833D01*
X520613Y-1072875D01*
X520747Y-1072958D01*
X520880Y-1073125D01*
G01X524267Y-1074500D02*
Y-1072000D01*
X524933D01*
X525147Y-1072125D01*
X525280Y-1072292D01*
X525333Y-1072625D01*
X525280Y-1072958D01*
X525120Y-1073167D01*
X524933Y-1073292D01*
X524267D01*
G01X524933D02*
X525333Y-1074500D01*
G01X526600Y-1073375D02*
X527453D01*
X527373Y-1073083D01*
X527240Y-1072917D01*
X527053Y-1072833D01*
X526867Y-1072875D01*
X526707Y-1073000D01*
X526600Y-1073292D01*
X526547Y-1073542D01*
Y-1073792D01*
X526600Y-1074042D01*
X526733Y-1074292D01*
X526893Y-1074458D01*
X527080Y-1074500D01*
X527267Y-1074417D01*
X527453Y-1074167D01*
G01X528720Y-1072833D02*
X529200Y-1074500D01*
X529680Y-1072833D01*
G01X531400Y-1074583D02*
X531347Y-1074542D01*
Y-1074458D01*
X531400Y-1074417D01*
X531453Y-1074458D01*
Y-1074542D01*
X531400Y-1074583D01*
G01X533600Y-1074500D02*
X533787Y-1074458D01*
X534000Y-1074333D01*
X534133Y-1074125D01*
X534187Y-1073833D01*
X534133Y-1073542D01*
X533973Y-1073292D01*
X533733Y-1073167D01*
X533467D01*
X533307Y-1073083D01*
X533173Y-1072875D01*
X533120Y-1072583D01*
X533200Y-1072292D01*
X533387Y-1072083D01*
X533600Y-1072000D01*
X533813Y-1072083D01*
X534000Y-1072292D01*
X534080Y-1072583D01*
X534027Y-1072875D01*
X533893Y-1073083D01*
X533733Y-1073167D01*
X533467D01*
X533227Y-1073292D01*
X533067Y-1073542D01*
X533013Y-1073833D01*
X533067Y-1074125D01*
X533200Y-1074333D01*
X533413Y-1074458D01*
X533600Y-1074500D01*
G01X536013Y-1073167D02*
X536120Y-1073042D01*
X536200Y-1072833D01*
X536253Y-1072542D01*
X536200Y-1072292D01*
X536093Y-1072125D01*
X535907Y-1072000D01*
X535187D01*
Y-1074500D01*
X536067D01*
X536253Y-1074333D01*
X536360Y-1074083D01*
X536413Y-1073792D01*
X536360Y-1073500D01*
X536200Y-1073250D01*
X536013Y-1073167D01*
X535187D01*
G01X-457143Y-1211429D02*
Y2242857D01*
X4308572D01*
Y-1211429D01*
X-457143D01*
G01X71650Y-1024800D02*
X69130Y-1024383D01*
X66925Y-1022717D01*
X65035Y-1020217D01*
X63775Y-1017300D01*
X63145Y-1013967D01*
Y-1010633D01*
X63775Y-1007300D01*
X65035Y-1004383D01*
X66925Y-1001884D01*
X69130Y-1000217D01*
X71650Y-999800D01*
X74170Y-1000217D01*
X76375Y-1001884D01*
X78265Y-1004383D01*
X79525Y-1007300D01*
X80155Y-1010633D01*
Y-1013967D01*
X79525Y-1017300D01*
X78265Y-1020217D01*
X76375Y-1022717D01*
X74170Y-1024383D01*
X71650Y-1024800D01*
G01X74170Y-1018133D02*
X77950Y-1024800D01*
G01X91495Y-1008134D02*
Y-1019800D01*
X92755Y-1022717D01*
X94645Y-1024383D01*
X96850Y-1024800D01*
X99055Y-1024383D01*
X100945Y-1022717D01*
X102205Y-1019800D01*
G01Y-1024800D02*
Y-1008134D01*
G01X127720Y-1024800D02*
Y-1008134D01*
G01Y-1011050D02*
X126460Y-1009384D01*
X124570Y-1008550D01*
X122365Y-1008134D01*
X120160Y-1008967D01*
X118270Y-1010633D01*
X117010Y-1013134D01*
X116380Y-1016467D01*
X117010Y-1019800D01*
X118270Y-1022301D01*
X120160Y-1023967D01*
X122365Y-1024800D01*
X124570Y-1024383D01*
X126460Y-1023134D01*
X127720Y-1021467D01*
G01X141895Y-1024800D02*
Y-1008134D01*
G01Y-1012300D02*
X143155Y-1010217D01*
X145045Y-1008550D01*
X147565Y-1008134D01*
X149770Y-1008550D01*
X151660Y-1010217D01*
X152605Y-1013134D01*
Y-1024800D01*
G01X172450Y-999800D02*
Y-1024800D01*
G01X168040Y-1008134D02*
X176860D01*
G01X203320Y-1024800D02*
Y-1008134D01*
G01Y-1011050D02*
X202060Y-1009384D01*
X200170Y-1008550D01*
X197965Y-1008134D01*
X195760Y-1008967D01*
X193870Y-1010633D01*
X192610Y-1013134D01*
X191980Y-1016467D01*
X192610Y-1019800D01*
X193870Y-1022301D01*
X195760Y-1023967D01*
X197965Y-1024800D01*
X200170Y-1024383D01*
X202060Y-1023134D01*
X203320Y-1021467D01*
G01X49820Y-1042350D02*
X51387D01*
Y-1044240D01*
X50917Y-1044870D01*
X50368Y-1045290D01*
X49585Y-1045500D01*
X48802Y-1045290D01*
X48253Y-1044870D01*
X47783Y-1044240D01*
X47470Y-1043505D01*
X47313Y-1042665D01*
Y-1041930D01*
X47470Y-1041300D01*
X47783Y-1040565D01*
X48253Y-1039935D01*
X48723Y-1039515D01*
X49350Y-1039200D01*
X49898D01*
X50525Y-1039410D01*
X50995Y-1039830D01*
G01X53927Y-1039200D02*
Y-1043715D01*
X54240Y-1044660D01*
X54867Y-1045290D01*
X55650Y-1045500D01*
X56433Y-1045290D01*
X57060Y-1044660D01*
X57373Y-1043715D01*
Y-1039200D01*
G01X61010D02*
X62890D01*
G01X61950D02*
Y-1045500D01*
G01X61010D02*
X62890D01*
G01X66605Y-1044660D02*
X67232Y-1045185D01*
X67937Y-1045500D01*
X68563D01*
X69190Y-1045185D01*
X69660Y-1044660D01*
X69895Y-1043925D01*
X69738Y-1043190D01*
X69347Y-1042560D01*
X68642Y-1042140D01*
X67702Y-1041930D01*
X67153Y-1041510D01*
X66918Y-1040775D01*
X67075Y-1040040D01*
X67467Y-1039515D01*
X68015Y-1039200D01*
X68563D01*
X69112Y-1039410D01*
X69582Y-1039935D01*
G01X72905Y-1045500D02*
Y-1039200D01*
G01X76195D02*
Y-1045500D01*
G01Y-1042350D02*
X72905D01*
G01X78892Y-1045500D02*
X80850Y-1039200D01*
X82808Y-1045500D01*
G01X82103Y-1043295D02*
X79597D01*
G01X85348Y-1045500D02*
Y-1039200D01*
X88952Y-1045500D01*
Y-1039200D01*
G01X98027Y-1045500D02*
Y-1039200D01*
X99593D01*
X100220Y-1039515D01*
X100690Y-1039935D01*
X101082Y-1040565D01*
X101395Y-1041300D01*
X101473Y-1042350D01*
X101395Y-1043400D01*
X101082Y-1044135D01*
X100690Y-1044765D01*
X100220Y-1045185D01*
X99593Y-1045500D01*
X98027D01*
G01X105110Y-1039200D02*
X106990D01*
G01X106050D02*
Y-1045500D01*
G01X105110D02*
X106990D01*
G01X110705Y-1044660D02*
X111332Y-1045185D01*
X112037Y-1045500D01*
X112663D01*
X113290Y-1045185D01*
X113760Y-1044660D01*
X113995Y-1043925D01*
X113838Y-1043190D01*
X113447Y-1042560D01*
X112742Y-1042140D01*
X111802Y-1041930D01*
X111253Y-1041510D01*
X111018Y-1040775D01*
X111175Y-1040040D01*
X111567Y-1039515D01*
X112115Y-1039200D01*
X112663D01*
X113212Y-1039410D01*
X113682Y-1039935D01*
G01X118650Y-1039200D02*
Y-1045500D01*
G01X116848Y-1039200D02*
X120452D01*
G01X124950Y-1045710D02*
X124793Y-1045605D01*
Y-1045395D01*
X124950Y-1045290D01*
X125107Y-1045395D01*
Y-1045605D01*
X124950Y-1045710D01*
G01X131093Y-1046655D02*
X131407Y-1045290D01*
G01X137550Y-1039200D02*
Y-1045500D01*
G01X135748Y-1039200D02*
X139352D01*
G01X141892Y-1045500D02*
X143850Y-1039200D01*
X145808Y-1045500D01*
G01X145103Y-1043295D02*
X142597D01*
G01X150150Y-1045500D02*
X149523Y-1045395D01*
X148975Y-1044975D01*
X148505Y-1044345D01*
X148192Y-1043610D01*
X148035Y-1042770D01*
Y-1041930D01*
X148192Y-1041090D01*
X148505Y-1040355D01*
X148975Y-1039725D01*
X149523Y-1039305D01*
X150150Y-1039200D01*
X150777Y-1039305D01*
X151325Y-1039725D01*
X151795Y-1040355D01*
X152108Y-1041090D01*
X152265Y-1041930D01*
Y-1042770D01*
X152108Y-1043610D01*
X151795Y-1044345D01*
X151325Y-1044975D01*
X150777Y-1045395D01*
X150150Y-1045500D01*
G01X156450D02*
Y-1042665D01*
X154883Y-1039200D01*
G01X158017D02*
X156450Y-1042665D01*
G01X161027Y-1039200D02*
Y-1043715D01*
X161340Y-1044660D01*
X161967Y-1045290D01*
X162750Y-1045500D01*
X163533Y-1045290D01*
X164160Y-1044660D01*
X164473Y-1043715D01*
Y-1039200D01*
G01X167092Y-1045500D02*
X169050Y-1039200D01*
X171008Y-1045500D01*
G01X170303Y-1043295D02*
X167797D01*
G01X173548Y-1045500D02*
Y-1039200D01*
X177152Y-1045500D01*
Y-1039200D01*
G01X51073Y-1049725D02*
X50603Y-1049410D01*
X50055Y-1049200D01*
X49428D01*
X48723Y-1049515D01*
X48175Y-1050040D01*
X47783Y-1050670D01*
X47470Y-1051720D01*
X47392Y-1052665D01*
X47548Y-1053610D01*
X47783Y-1054240D01*
X48253Y-1054870D01*
X48802Y-1055290D01*
X49350Y-1055500D01*
X49898D01*
X50447Y-1055290D01*
X50917Y-1054975D01*
X51308Y-1054555D01*
G01X54710Y-1049200D02*
X56590D01*
G01X55650D02*
Y-1055500D01*
G01X54710D02*
X56590D01*
G01X61950Y-1049200D02*
Y-1055500D01*
G01X60148Y-1049200D02*
X63752D01*
G01X68250Y-1055500D02*
Y-1052665D01*
X66683Y-1049200D01*
G01X69817D02*
X68250Y-1052665D01*
G01X79127Y-1054240D02*
X79597Y-1054975D01*
X80223Y-1055395D01*
X80928Y-1055500D01*
X81555Y-1055395D01*
X82182Y-1054870D01*
X82573Y-1054240D01*
X82652Y-1053610D01*
X82495Y-1052875D01*
X81947Y-1052350D01*
X81398Y-1052140D01*
X80693D01*
G01X81398D02*
X81868Y-1051825D01*
X82260Y-1051300D01*
X82417Y-1050670D01*
X82260Y-1050040D01*
X81868Y-1049515D01*
X81163Y-1049200D01*
X80458Y-1049305D01*
X79753Y-1049725D01*
G01X85427Y-1054240D02*
X85897Y-1054975D01*
X86523Y-1055395D01*
X87228Y-1055500D01*
X87855Y-1055395D01*
X88482Y-1054870D01*
X88873Y-1054240D01*
X88952Y-1053610D01*
X88795Y-1052875D01*
X88247Y-1052350D01*
X87698Y-1052140D01*
X86993D01*
G01X87698D02*
X88168Y-1051825D01*
X88560Y-1051300D01*
X88717Y-1050670D01*
X88560Y-1050040D01*
X88168Y-1049515D01*
X87463Y-1049200D01*
X86758Y-1049305D01*
X86053Y-1049725D01*
G01X91727Y-1054240D02*
X92197Y-1054975D01*
X92823Y-1055395D01*
X93528Y-1055500D01*
X94155Y-1055395D01*
X94782Y-1054870D01*
X95173Y-1054240D01*
X95252Y-1053610D01*
X95095Y-1052875D01*
X94547Y-1052350D01*
X93998Y-1052140D01*
X93293D01*
G01X93998D02*
X94468Y-1051825D01*
X94860Y-1051300D01*
X95017Y-1050670D01*
X94860Y-1050040D01*
X94468Y-1049515D01*
X93763Y-1049200D01*
X93058Y-1049305D01*
X92353Y-1049725D01*
G01X99593Y-1055500D02*
X99750Y-1054135D01*
X99985Y-1052980D01*
X100298Y-1051930D01*
X100690Y-1050775D01*
X101317Y-1049200D01*
X98183D01*
G01X105893Y-1055500D02*
X106050Y-1054135D01*
X106285Y-1052980D01*
X106598Y-1051930D01*
X106990Y-1050775D01*
X107617Y-1049200D01*
X104483D01*
G01X112193Y-1056655D02*
X112507Y-1055290D01*
G01X118650Y-1049200D02*
Y-1055500D01*
G01X116848Y-1049200D02*
X120452D01*
G01X122992Y-1055500D02*
X124950Y-1049200D01*
X126908Y-1055500D01*
G01X126203Y-1053295D02*
X123697D01*
G01X130310Y-1049200D02*
X132190D01*
G01X131250D02*
Y-1055500D01*
G01X130310D02*
X132190D01*
G01X135200Y-1049200D02*
X136297Y-1055500D01*
X137550Y-1049200D01*
X138803Y-1055500D01*
X139900Y-1049200D01*
G01X141892Y-1055500D02*
X143850Y-1049200D01*
X145808Y-1055500D01*
G01X145103Y-1053295D02*
X142597D01*
G01X148348Y-1055500D02*
Y-1049200D01*
X151952Y-1055500D01*
Y-1049200D01*
G01X162358Y-1057600D02*
X161575Y-1056550D01*
X161183Y-1055500D01*
Y-1051300D01*
X161575Y-1050250D01*
X162358Y-1049200D01*
G01X173783Y-1055500D02*
Y-1049200D01*
X175742D01*
X176368Y-1049515D01*
X176760Y-1049935D01*
X176917Y-1050775D01*
X176760Y-1051615D01*
X176290Y-1052140D01*
X175742Y-1052455D01*
X173783D01*
G01X175742D02*
X176917Y-1055500D01*
G01X181650Y-1055710D02*
X181493Y-1055605D01*
Y-1055395D01*
X181650Y-1055290D01*
X181807Y-1055395D01*
Y-1055605D01*
X181650Y-1055710D01*
G01X187950Y-1055500D02*
X187323Y-1055395D01*
X186775Y-1054975D01*
X186305Y-1054345D01*
X185992Y-1053610D01*
X185835Y-1052770D01*
Y-1051930D01*
X185992Y-1051090D01*
X186305Y-1050355D01*
X186775Y-1049725D01*
X187323Y-1049305D01*
X187950Y-1049200D01*
X188577Y-1049305D01*
X189125Y-1049725D01*
X189595Y-1050355D01*
X189908Y-1051090D01*
X190065Y-1051930D01*
Y-1052770D01*
X189908Y-1053610D01*
X189595Y-1054345D01*
X189125Y-1054975D01*
X188577Y-1055395D01*
X187950Y-1055500D01*
G01X194250Y-1055710D02*
X194093Y-1055605D01*
Y-1055395D01*
X194250Y-1055290D01*
X194407Y-1055395D01*
Y-1055605D01*
X194250Y-1055710D01*
G01X202273Y-1049725D02*
X201803Y-1049410D01*
X201255Y-1049200D01*
X200628D01*
X199923Y-1049515D01*
X199375Y-1050040D01*
X198983Y-1050670D01*
X198670Y-1051720D01*
X198592Y-1052665D01*
X198748Y-1053610D01*
X198983Y-1054240D01*
X199453Y-1054870D01*
X200002Y-1055290D01*
X200550Y-1055500D01*
X201098D01*
X201647Y-1055290D01*
X202117Y-1054975D01*
X202508Y-1054555D01*
G01X206850Y-1055710D02*
X206693Y-1055605D01*
Y-1055395D01*
X206850Y-1055290D01*
X207007Y-1055395D01*
Y-1055605D01*
X206850Y-1055710D01*
G01X213542Y-1057600D02*
X214325Y-1056550D01*
X214717Y-1055500D01*
Y-1051300D01*
X214325Y-1050250D01*
X213542Y-1049200D01*
G01X47548Y-1035500D02*
Y-1029200D01*
X51152Y-1035500D01*
Y-1029200D01*
G01X55650Y-1035500D02*
X55023Y-1035395D01*
X54475Y-1034975D01*
X54005Y-1034345D01*
X53692Y-1033610D01*
X53535Y-1032770D01*
Y-1031930D01*
X53692Y-1031090D01*
X54005Y-1030355D01*
X54475Y-1029725D01*
X55023Y-1029305D01*
X55650Y-1029200D01*
X56277Y-1029305D01*
X56825Y-1029725D01*
X57295Y-1030355D01*
X57608Y-1031090D01*
X57765Y-1031930D01*
Y-1032770D01*
X57608Y-1033610D01*
X57295Y-1034345D01*
X56825Y-1034975D01*
X56277Y-1035395D01*
X55650Y-1035500D01*
G01X61950Y-1035710D02*
X61793Y-1035605D01*
Y-1035395D01*
X61950Y-1035290D01*
X62107Y-1035395D01*
Y-1035605D01*
X61950Y-1035710D01*
G01X66762Y-1030250D02*
X67232Y-1029620D01*
X67780Y-1029305D01*
X68407Y-1029200D01*
X69190Y-1029410D01*
X69738Y-1029935D01*
X69895Y-1030565D01*
X69817Y-1031195D01*
X69503Y-1031720D01*
X67937Y-1032770D01*
X67232Y-1033505D01*
X66762Y-1034555D01*
X66605Y-1035500D01*
X69895D01*
G01X74550D02*
Y-1029200D01*
X73610Y-1030460D01*
G01Y-1035500D02*
X75490D01*
G01X80850D02*
Y-1029200D01*
X79910Y-1030460D01*
G01Y-1035500D02*
X81790D01*
G01X86993Y-1036655D02*
X87307Y-1035290D01*
G01X91100Y-1029200D02*
X92197Y-1035500D01*
X93450Y-1029200D01*
X94703Y-1035500D01*
X95800Y-1029200D01*
G01X101317Y-1035500D02*
X98183D01*
Y-1029200D01*
X101317D01*
G01X100063Y-1032245D02*
X98183D01*
G01X104248Y-1035500D02*
Y-1029200D01*
X107852Y-1035500D01*
Y-1029200D01*
G01X110705Y-1035500D02*
Y-1029200D01*
G01X113995D02*
Y-1035500D01*
G01Y-1032350D02*
X110705D01*
G01X116927Y-1029200D02*
Y-1033715D01*
X117240Y-1034660D01*
X117867Y-1035290D01*
X118650Y-1035500D01*
X119433Y-1035290D01*
X120060Y-1034660D01*
X120373Y-1033715D01*
Y-1029200D01*
G01X122992Y-1035500D02*
X124950Y-1029200D01*
X126908Y-1035500D01*
G01X126203Y-1033295D02*
X123697D01*
G01X136062Y-1030250D02*
X136532Y-1029620D01*
X137080Y-1029305D01*
X137707Y-1029200D01*
X138490Y-1029410D01*
X139038Y-1029935D01*
X139195Y-1030565D01*
X139117Y-1031195D01*
X138803Y-1031720D01*
X137237Y-1032770D01*
X136532Y-1033505D01*
X136062Y-1034555D01*
X135905Y-1035500D01*
X139195D01*
G01X142048D02*
Y-1029200D01*
X145652Y-1035500D01*
Y-1029200D01*
G01X148427Y-1035500D02*
Y-1029200D01*
X149993D01*
X150620Y-1029515D01*
X151090Y-1029935D01*
X151482Y-1030565D01*
X151795Y-1031300D01*
X151873Y-1032350D01*
X151795Y-1033400D01*
X151482Y-1034135D01*
X151090Y-1034765D01*
X150620Y-1035185D01*
X149993Y-1035500D01*
X148427D01*
G01X161183D02*
Y-1029200D01*
X163142D01*
X163768Y-1029515D01*
X164160Y-1029935D01*
X164317Y-1030775D01*
X164160Y-1031615D01*
X163690Y-1032140D01*
X163142Y-1032455D01*
X161183D01*
G01X163142D02*
X164317Y-1035500D01*
G01X167327D02*
Y-1029200D01*
X168893D01*
X169520Y-1029515D01*
X169990Y-1029935D01*
X170382Y-1030565D01*
X170695Y-1031300D01*
X170773Y-1032350D01*
X170695Y-1033400D01*
X170382Y-1034135D01*
X169990Y-1034765D01*
X169520Y-1035185D01*
X168893Y-1035500D01*
X167327D01*
G01X175350Y-1035710D02*
X175193Y-1035605D01*
Y-1035395D01*
X175350Y-1035290D01*
X175507Y-1035395D01*
Y-1035605D01*
X175350Y-1035710D01*
G01X243000Y-1004500D02*
Y-1012500D01*
X247000D01*
G01X254800D02*
Y-1007167D01*
G01Y-1008100D02*
X254400Y-1007567D01*
X253800Y-1007300D01*
X253100Y-1007167D01*
X252400Y-1007433D01*
X251800Y-1007967D01*
X251400Y-1008767D01*
X251200Y-1009833D01*
X251400Y-1010900D01*
X251800Y-1011700D01*
X252400Y-1012233D01*
X253100Y-1012500D01*
X253800Y-1012367D01*
X254400Y-1011967D01*
X254800Y-1011434D01*
G01X258900Y-1014900D02*
X259500Y-1015167D01*
X260300Y-1014900D01*
X260800Y-1014367D01*
X261200Y-1013700D01*
X261800Y-1011567D01*
X263100Y-1007167D01*
G01X259900D02*
X261800Y-1011567D01*
G01X267500Y-1008900D02*
X270700D01*
X270400Y-1007967D01*
X269900Y-1007433D01*
X269200Y-1007167D01*
X268500Y-1007300D01*
X267900Y-1007700D01*
X267500Y-1008633D01*
X267300Y-1009434D01*
Y-1010233D01*
X267500Y-1011033D01*
X268000Y-1011833D01*
X268600Y-1012367D01*
X269300Y-1012500D01*
X270000Y-1012233D01*
X270700Y-1011434D01*
G01X275600Y-1012500D02*
Y-1007167D01*
G01Y-1008233D02*
X276100Y-1007700D01*
X276600Y-1007300D01*
X277300Y-1007167D01*
X277800Y-1007300D01*
X278400Y-1007700D01*
G01X262100Y-1054500D02*
X265900D01*
X262100Y-1062500D01*
X265900D01*
G01X272000Y-1057167D02*
Y-1062500D01*
G01Y-1055033D02*
X271800Y-1054900D01*
Y-1054633D01*
X272000Y-1054500D01*
X272200Y-1054633D01*
Y-1054900D01*
X272000Y-1055033D01*
G01X278700Y-1059833D02*
X281300D01*
G01X286200Y-1065167D02*
Y-1057167D01*
G01Y-1058367D02*
X286700Y-1057700D01*
X287200Y-1057300D01*
X288000Y-1057167D01*
X288700Y-1057300D01*
X289400Y-1057967D01*
X289700Y-1058900D01*
X289800Y-1059833D01*
X289700Y-1060767D01*
X289400Y-1061700D01*
X288800Y-1062233D01*
X288000Y-1062500D01*
X287300Y-1062367D01*
X286600Y-1061967D01*
X286200Y-1061434D01*
G01X296000Y-1057167D02*
Y-1062500D01*
G01Y-1055033D02*
X295800Y-1054900D01*
Y-1054633D01*
X296000Y-1054500D01*
X296200Y-1054633D01*
Y-1054900D01*
X296000Y-1055033D01*
G01X302300Y-1062500D02*
Y-1057167D01*
G01Y-1058500D02*
X302700Y-1057833D01*
X303300Y-1057300D01*
X304100Y-1057167D01*
X304800Y-1057300D01*
X305400Y-1057833D01*
X305700Y-1058767D01*
Y-1062500D01*
G01X310600Y-1064500D02*
X311300Y-1065033D01*
X312100Y-1065167D01*
X312800Y-1065033D01*
X313400Y-1064367D01*
X313800Y-1063433D01*
Y-1057167D01*
G01Y-1058233D02*
X313400Y-1057700D01*
X312800Y-1057300D01*
X312100Y-1057167D01*
X311300Y-1057433D01*
X310800Y-1057967D01*
X310400Y-1058900D01*
X310200Y-1059833D01*
X310300Y-1060633D01*
X310700Y-1061567D01*
X311300Y-1062233D01*
X312100Y-1062500D01*
X312700Y-1062367D01*
X313400Y-1061833D01*
X313800Y-1061300D01*
G01X277100Y-1033500D02*
X279100D01*
Y-1035900D01*
X278500Y-1036700D01*
X277800Y-1037233D01*
X276800Y-1037500D01*
X275800Y-1037233D01*
X275100Y-1036700D01*
X274500Y-1035900D01*
X274100Y-1034967D01*
X273900Y-1033900D01*
Y-1032967D01*
X274100Y-1032167D01*
X274500Y-1031233D01*
X275100Y-1030433D01*
X275700Y-1029900D01*
X276500Y-1029500D01*
X277200D01*
X278000Y-1029767D01*
X278600Y-1030300D01*
G01X282200Y-1037500D02*
Y-1029500D01*
X286800Y-1037500D01*
Y-1029500D01*
G01X290300Y-1037500D02*
Y-1029500D01*
X292300D01*
X293100Y-1029900D01*
X293700Y-1030433D01*
X294200Y-1031233D01*
X294600Y-1032167D01*
X294700Y-1033500D01*
X294600Y-1034833D01*
X294200Y-1035767D01*
X293700Y-1036567D01*
X293100Y-1037100D01*
X292300Y-1037500D01*
X290300D01*
G01X298600Y-1030833D02*
X299200Y-1030033D01*
X299900Y-1029633D01*
X300700Y-1029500D01*
X301700Y-1029767D01*
X302400Y-1030433D01*
X302600Y-1031233D01*
X302500Y-1032034D01*
X302100Y-1032700D01*
X300100Y-1034033D01*
X299200Y-1034967D01*
X298600Y-1036300D01*
X298400Y-1037500D01*
X302600D01*
G01X296300Y-1012500D02*
X296500Y-1010767D01*
X296800Y-1009300D01*
X297200Y-1007967D01*
X297700Y-1006500D01*
X298500Y-1004500D01*
X294500D01*
G01X369600Y-1055833D02*
X370200Y-1055033D01*
X370900Y-1054633D01*
X371700Y-1054500D01*
X372700Y-1054767D01*
X373400Y-1055433D01*
X373600Y-1056233D01*
X373500Y-1057034D01*
X373100Y-1057700D01*
X371100Y-1059033D01*
X370200Y-1059967D01*
X369600Y-1061300D01*
X369400Y-1062500D01*
X373600D01*
G01X379500Y-1054500D02*
X378700Y-1054767D01*
X378100Y-1055433D01*
X377700Y-1056233D01*
X377400Y-1057300D01*
X377300Y-1058500D01*
X377400Y-1059700D01*
X377700Y-1060767D01*
X378100Y-1061567D01*
X378700Y-1062233D01*
X379500Y-1062500D01*
X380300Y-1062233D01*
X380900Y-1061567D01*
X381300Y-1060767D01*
X381600Y-1059700D01*
X381700Y-1058500D01*
X381600Y-1057300D01*
X381300Y-1056233D01*
X380900Y-1055433D01*
X380300Y-1054767D01*
X379500Y-1054500D01*
G01X385600Y-1055833D02*
X386200Y-1055033D01*
X386900Y-1054633D01*
X387700Y-1054500D01*
X388700Y-1054767D01*
X389400Y-1055433D01*
X389600Y-1056233D01*
X389500Y-1057034D01*
X389100Y-1057700D01*
X387100Y-1059033D01*
X386200Y-1059967D01*
X385600Y-1061300D01*
X385400Y-1062500D01*
X389600D01*
G01X393600Y-1055833D02*
X394200Y-1055033D01*
X394900Y-1054633D01*
X395700Y-1054500D01*
X396700Y-1054767D01*
X397400Y-1055433D01*
X397600Y-1056233D01*
X397500Y-1057034D01*
X397100Y-1057700D01*
X395100Y-1059033D01*
X394200Y-1059967D01*
X393600Y-1061300D01*
X393400Y-1062500D01*
X397600D01*
G01X401700Y-1062767D02*
X405300Y-1054500D01*
G01X411500Y-1062500D02*
Y-1054500D01*
X410300Y-1056100D01*
G01Y-1062500D02*
X412700D01*
G01X417600Y-1055833D02*
X418200Y-1055033D01*
X418900Y-1054633D01*
X419700Y-1054500D01*
X420700Y-1054767D01*
X421400Y-1055433D01*
X421600Y-1056233D01*
X421500Y-1057034D01*
X421100Y-1057700D01*
X419100Y-1059033D01*
X418200Y-1059967D01*
X417600Y-1061300D01*
X417400Y-1062500D01*
X421600D01*
G01X425700Y-1062767D02*
X429300Y-1054500D01*
G01X435500Y-1062500D02*
Y-1054500D01*
X434300Y-1056100D01*
G01Y-1062500D02*
X436700D01*
G01X441300Y-1060900D02*
X441900Y-1061833D01*
X442700Y-1062367D01*
X443600Y-1062500D01*
X444400Y-1062367D01*
X445200Y-1061700D01*
X445700Y-1060900D01*
X445800Y-1060100D01*
X445600Y-1059167D01*
X444900Y-1058500D01*
X444200Y-1058233D01*
X443300D01*
G01X444200D02*
X444800Y-1057833D01*
X445300Y-1057167D01*
X445500Y-1056367D01*
X445300Y-1055567D01*
X444800Y-1054900D01*
X443900Y-1054500D01*
X443000Y-1054633D01*
X442100Y-1055167D01*
G01X369300Y-1040000D02*
Y-1032000D01*
X371300D01*
X372100Y-1032400D01*
X372700Y-1032933D01*
X373200Y-1033733D01*
X373600Y-1034667D01*
X373700Y-1036000D01*
X373600Y-1037333D01*
X373200Y-1038267D01*
X372700Y-1039067D01*
X372100Y-1039600D01*
X371300Y-1040000D01*
X369300D01*
G01X377000D02*
X379500Y-1032000D01*
X382000Y-1040000D01*
G01X381100Y-1037200D02*
X377900D01*
G01X385600Y-1040000D02*
Y-1032000D01*
X389400D01*
G01X388000Y-1035867D02*
X385600D01*
G01X395500Y-1032000D02*
X394700Y-1032267D01*
X394100Y-1032933D01*
X393700Y-1033733D01*
X393400Y-1034800D01*
X393300Y-1036000D01*
X393400Y-1037200D01*
X393700Y-1038267D01*
X394100Y-1039067D01*
X394700Y-1039733D01*
X395500Y-1040000D01*
X396300Y-1039733D01*
X396900Y-1039067D01*
X397300Y-1038267D01*
X397600Y-1037200D01*
X397700Y-1036000D01*
X397600Y-1034800D01*
X397300Y-1033733D01*
X396900Y-1032933D01*
X396300Y-1032267D01*
X395500Y-1032000D01*
G01X403500D02*
Y-1040000D01*
G01X401200Y-1032000D02*
X405800D01*
G01X409500Y-1040000D02*
Y-1032000D01*
X411900D01*
X412700Y-1032400D01*
X413300Y-1033333D01*
X413500Y-1034400D01*
X413300Y-1035467D01*
X412800Y-1036267D01*
X411900Y-1036667D01*
X409500D01*
G01X420300Y-1035733D02*
X420700Y-1035333D01*
X421000Y-1034667D01*
X421200Y-1033733D01*
X421000Y-1032933D01*
X420600Y-1032400D01*
X419900Y-1032000D01*
X417200D01*
Y-1040000D01*
X420500D01*
X421200Y-1039467D01*
X421600Y-1038667D01*
X421800Y-1037733D01*
X421600Y-1036800D01*
X421000Y-1036000D01*
X420300Y-1035733D01*
X417200D01*
G01X427500Y-1040000D02*
Y-1032000D01*
X426300Y-1033600D01*
G01Y-1040000D02*
X428700D01*
G01X433000D02*
X435500Y-1032000D01*
X438000Y-1040000D01*
G01X437100Y-1037200D02*
X433900D01*
G01X441600Y-1040000D02*
Y-1032000D01*
X445400D01*
G01X444000Y-1035867D02*
X441600D01*
G01X451500Y-1032000D02*
X450700Y-1032267D01*
X450100Y-1032933D01*
X449700Y-1033733D01*
X449400Y-1034800D01*
X449300Y-1036000D01*
X449400Y-1037200D01*
X449700Y-1038267D01*
X450100Y-1039067D01*
X450700Y-1039733D01*
X451500Y-1040000D01*
X452300Y-1039733D01*
X452900Y-1039067D01*
X453300Y-1038267D01*
X453600Y-1037200D01*
X453700Y-1036000D01*
X453600Y-1034800D01*
X453300Y-1033733D01*
X452900Y-1032933D01*
X452300Y-1032267D01*
X451500Y-1032000D01*
G01X389600Y-1012500D02*
Y-1004500D01*
X393400D01*
G01X392000Y-1008367D02*
X389600D01*
G01X399500Y-1004500D02*
X398700Y-1004767D01*
X398100Y-1005433D01*
X397700Y-1006233D01*
X397400Y-1007300D01*
X397300Y-1008500D01*
X397400Y-1009700D01*
X397700Y-1010767D01*
X398100Y-1011567D01*
X398700Y-1012233D01*
X399500Y-1012500D01*
X400300Y-1012233D01*
X400900Y-1011567D01*
X401300Y-1010767D01*
X401600Y-1009700D01*
X401700Y-1008500D01*
X401600Y-1007300D01*
X401300Y-1006233D01*
X400900Y-1005433D01*
X400300Y-1004767D01*
X399500Y-1004500D01*
G01X407500D02*
Y-1012500D01*
G01X405200Y-1004500D02*
X409800D01*
G01X412500Y-1015167D02*
X418500D01*
G01X421500Y-1012500D02*
Y-1004500D01*
X423900D01*
X424700Y-1004900D01*
X425300Y-1005833D01*
X425500Y-1006900D01*
X425300Y-1007967D01*
X424800Y-1008767D01*
X423900Y-1009167D01*
X421500D01*
G01X429300Y-1012500D02*
Y-1004500D01*
X431300D01*
X432100Y-1004900D01*
X432700Y-1005433D01*
X433200Y-1006233D01*
X433600Y-1007167D01*
X433700Y-1008500D01*
X433600Y-1009833D01*
X433200Y-1010767D01*
X432700Y-1011567D01*
X432100Y-1012100D01*
X431300Y-1012500D01*
X429300D01*
G01X440300Y-1008233D02*
X440700Y-1007833D01*
X441000Y-1007167D01*
X441200Y-1006233D01*
X441000Y-1005433D01*
X440600Y-1004900D01*
X439900Y-1004500D01*
X437200D01*
Y-1012500D01*
X440500D01*
X441200Y-1011967D01*
X441600Y-1011167D01*
X441800Y-1010233D01*
X441600Y-1009300D01*
X441000Y-1008500D01*
X440300Y-1008233D01*
X437200D01*
G01X444500Y-1015167D02*
X450500D01*
G01X456300Y-1008233D02*
X456700Y-1007833D01*
X457000Y-1007167D01*
X457200Y-1006233D01*
X457000Y-1005433D01*
X456600Y-1004900D01*
X455900Y-1004500D01*
X453200D01*
Y-1012500D01*
X456500D01*
X457200Y-1011967D01*
X457600Y-1011167D01*
X457800Y-1010233D01*
X457600Y-1009300D01*
X457000Y-1008500D01*
X456300Y-1008233D01*
X453200D01*
G01X461300Y-1012500D02*
Y-1004500D01*
X463300D01*
X464100Y-1004900D01*
X464700Y-1005433D01*
X465200Y-1006233D01*
X465600Y-1007167D01*
X465700Y-1008500D01*
X465600Y-1009833D01*
X465200Y-1010767D01*
X464700Y-1011567D01*
X464100Y-1012100D01*
X463300Y-1012500D01*
X461300D01*
G01X468500Y-1015167D02*
X474500D01*
G01X480100Y-1008500D02*
X482100D01*
Y-1010900D01*
X481500Y-1011700D01*
X480800Y-1012233D01*
X479800Y-1012500D01*
X478800Y-1012233D01*
X478100Y-1011700D01*
X477500Y-1010900D01*
X477100Y-1009967D01*
X476900Y-1008900D01*
Y-1007967D01*
X477100Y-1007167D01*
X477500Y-1006233D01*
X478100Y-1005433D01*
X478700Y-1004900D01*
X479500Y-1004500D01*
X480200D01*
X481000Y-1004767D01*
X481600Y-1005300D01*
G01X485500Y-1012500D02*
Y-1004500D01*
X487900D01*
X488700Y-1004900D01*
X489300Y-1005833D01*
X489500Y-1006900D01*
X489300Y-1007967D01*
X488800Y-1008767D01*
X487900Y-1009167D01*
X485500D01*
G01X493300Y-1004500D02*
Y-1010233D01*
X493700Y-1011434D01*
X494500Y-1012233D01*
X495500Y-1012500D01*
X496500Y-1012233D01*
X497300Y-1011434D01*
X497700Y-1010233D01*
Y-1004500D01*
G01X458000Y-1065500D02*
Y-1057500D01*
X456800Y-1059100D01*
G01Y-1065500D02*
X459200D01*
G01X464100Y-1062167D02*
X464800Y-1061233D01*
X465400Y-1060700D01*
X466200Y-1060433D01*
X466900Y-1060700D01*
X467400Y-1061233D01*
X467800Y-1062033D01*
X467900Y-1062967D01*
X467800Y-1063767D01*
X467400Y-1064567D01*
X466800Y-1065233D01*
X466100Y-1065500D01*
X465300Y-1065233D01*
X464600Y-1064434D01*
X464200Y-1063233D01*
X464100Y-1061900D01*
X464300Y-1060167D01*
X464600Y-1059233D01*
X465100Y-1058300D01*
X465800Y-1057633D01*
X466500Y-1057500D01*
X467200Y-1057767D01*
X467700Y-1058433D01*
G01X474000Y-1065767D02*
X473800Y-1065633D01*
Y-1065367D01*
X474000Y-1065233D01*
X474200Y-1065367D01*
Y-1065633D01*
X474000Y-1065767D01*
G01X480100Y-1062167D02*
X480800Y-1061233D01*
X481400Y-1060700D01*
X482200Y-1060433D01*
X482900Y-1060700D01*
X483400Y-1061233D01*
X483800Y-1062033D01*
X483900Y-1062967D01*
X483800Y-1063767D01*
X483400Y-1064567D01*
X482800Y-1065233D01*
X482100Y-1065500D01*
X481300Y-1065233D01*
X480600Y-1064434D01*
X480200Y-1063233D01*
X480100Y-1061900D01*
X480300Y-1060167D01*
X480600Y-1059233D01*
X481100Y-1058300D01*
X481800Y-1057633D01*
X482500Y-1057500D01*
X483200Y-1057767D01*
X483700Y-1058433D01*
G01X503000Y-1065500D02*
Y-1057500D01*
X501800Y-1059100D01*
G01Y-1065500D02*
X504200D01*
G01X510800D02*
X511000Y-1063767D01*
X511300Y-1062300D01*
X511700Y-1060967D01*
X512200Y-1059500D01*
X513000Y-1057500D01*
X509000D01*
G01X519000Y-1065767D02*
X518800Y-1065633D01*
Y-1065367D01*
X519000Y-1065233D01*
X519200Y-1065367D01*
Y-1065633D01*
X519000Y-1065767D01*
G01X525100Y-1058833D02*
X525700Y-1058033D01*
X526400Y-1057633D01*
X527200Y-1057500D01*
X528200Y-1057767D01*
X528900Y-1058433D01*
X529100Y-1059233D01*
X529000Y-1060034D01*
X528600Y-1060700D01*
X526600Y-1062033D01*
X525700Y-1062967D01*
X525100Y-1064300D01*
X524900Y-1065500D01*
X529100D01*
G01X523100Y-1040500D02*
Y-1032500D01*
X526900D01*
G01X525500Y-1036367D02*
X523100D01*
M02*
